G04 ================== begin FILE IDENTIFICATION RECORD ==================*
G04 Layout Name:  13948-1b.brd*
G04 Film Name:    L3*
G04 File Format:  Gerber RS274X*
G04 File Origin:  Cadence Allegro 16.5-S045*
G04 Origin Date:  Thu Nov 13 15:46:11 2014*
G04 *
G04 Layer:  VIA CLASS/L3*
G04 Layer:  PIN/L3*
G04 Layer:  ETCH/L3*
G04 Layer:  DRAWING FORMAT/LAYER_PCB_STORY*
G04 Layer:  DRAWING FORMAT/LAYER_L3*
G04 *
G04 Offset:    (0.00 0.00)*
G04 Mirror:    No*
G04 Mode:      Positive*
G04 Rotation:  0*
G04 FullContactRelief:  No*
G04 UndefLineWidth:     6.00*
G04 ================== end FILE IDENTIFICATION RECORD ====================*
%FSLAX35Y35*MOIN*%
%IR0*IPPOS*OFA0.00000B0.00000*MIA0B0*SFA1.00000B1.00000*%
%ADD13C,.02*%
%ADD12C,.022*%
%ADD21C,.05*%
%ADD18C,.043*%
%ADD15C,.061*%
%ADD19C,.054*%
%ADD16C,.045*%
%ADD14C,.046*%
%ADD10C,.028*%
%ADD22C,.056*%
%ADD20C,.058*%
%ADD17C,.078*%
%ADD11C,.115*%
%ADD23C,.01*%
%ADD24C,.012*%
%ADD25C,.04*%
%ADD26C,.025*%
%ADD27C,.004*%
%ADD28C,.005*%
%ADD29C,.006*%
%ADD30C,.007*%
%ADD31C,.0035*%
%ADD41C,.03004*%
%ADD47C,.03204*%
%ADD40C,.05204*%
%ADD39C,.07004*%
%ADD52C,.08004*%
%ADD50C,.06204*%
%ADD37C,.04404*%
%ADD43C,.09004*%
%ADD42C,.03604*%
%ADD53C,.02804*%
%ADD36C,.04604*%
%ADD51C,.05604*%
%ADD38C,.07404*%
%ADD55C,.05804*%
%ADD49C,.06704*%
%ADD33C,.08504*%
%ADD32C,.08604*%
%ADD46C,.07804*%
%ADD54O,.21302X.15002*%
%ADD44C,.10204*%
%ADD45C,.13104*%
%ADD34C,.15004*%
%ADD48C,.16204*%
%ADD35C,.13904*%
G75*
%LPD*%
G75*
G36*
G01X306002Y3000D02*
X306001Y3001D01*
X297999D01*
X296500Y4500D01*
Y66000D01*
X292500Y70000D01*
X248500D01*
X247000Y71500D01*
Y227500D01*
X243000Y231500D01*
X226435D01*
G02X226187Y232214I0J400D01*
G03X221843I-2172J2747D01*
G02X221595Y231500I-248J-314D01*
G01X117000D01*
X111500Y237000D01*
Y304500D01*
X105500Y310500D01*
X10500D01*
X3500Y317500D01*
Y840000D01*
X5000Y841500D01*
X45500D01*
X56500Y830500D01*
X65000D01*
X67500Y833000D01*
Y834163D01*
G03Y837277I-1696J1557D01*
G01Y849000D01*
X71000Y852500D01*
X88500D01*
X90500Y850500D01*
Y849714D01*
G02X89779Y849476I-400J0D01*
G03Y846738I-1851J-1369D01*
G02X90500Y846500I321J-238D01*
G01Y837150D01*
G03X91362Y833620I1804J-1430D01*
G01X91395Y833605D01*
X93000Y832000D01*
X110547D01*
G02X110943Y831544I0J-400D01*
G03X115501I2279J-322D01*
G02X115897Y832000I396J56D01*
G01X135500D01*
X140500Y827000D01*
Y804500D01*
X142500Y802500D01*
X144774D01*
G03X147834I1530J1720D01*
G01X167000D01*
X184750Y820250D01*
X246750D01*
X252798Y826298D01*
X255705D01*
X271705Y842298D01*
X399205D01*
X401906Y845000D01*
X405000D01*
X418798Y858798D01*
X493202D01*
X499500Y852500D01*
X665594D01*
X668295Y849798D01*
X713705D01*
X716406Y852500D01*
X719304D01*
X719332Y852332D01*
G03X719419Y851964I2569J413D01*
G02X719166Y851465I-381J-120D01*
G03X722481Y849786I834J-2465D01*
G02X722734Y850285I381J120D01*
G03X724468Y852332I-834J2465D01*
G01X724496Y852500D01*
X808032D01*
G02X808397Y851937I0J-400D01*
G03X812603I2103J-937D01*
G02X812968Y852500I365J163D01*
G01X816000D01*
X820147Y848353D01*
G02X820070Y847726I-282J-284D01*
G03X823226Y844570I1180J-1976D01*
G02X823853Y844647I343J-205D01*
G01X831000Y837500D01*
Y826500D01*
X828686Y824186D01*
X593267D01*
X566353Y797272D01*
X142841D01*
G03X138899Y796630I-1787J-1452D01*
G01X138850Y796500D01*
X137500D01*
X137000Y796000D01*
X91500D01*
X86500Y801000D01*
X84000D01*
X80000Y797000D01*
Y791000D01*
X81500Y789500D01*
X148000D01*
X148221Y789279D01*
X148234Y789257D01*
G03X151507Y788500I1991J1155D01*
G01X550000D01*
X553000Y785500D01*
Y766500D01*
X541652Y755152D01*
X74278D01*
X73578Y754452D01*
X72983D01*
X66203Y747672D01*
X57091D01*
G03Y744768I-1787J-1452D01*
G01X65334D01*
G02X65617Y744086I0J-400D01*
G01X63361Y741829D01*
X63251Y741856D01*
G03X64982Y739289I-547J-2236D01*
G01X64992Y739355D01*
X76185Y750548D01*
X80000D01*
Y750500D01*
X80500Y750000D01*
X546000D01*
X568000Y772000D01*
X675754D01*
G03X679246I1746J1500D01*
G01X733191D01*
X733204Y771815D01*
G03X737796I2296J169D01*
G01X737809Y772000D01*
X871000D01*
X874000Y769000D01*
Y749000D01*
X872000Y747000D01*
X667000D01*
X632620Y712620D01*
X398260D01*
G02X397926Y713239I0J400D01*
G03X394074I-1926J1261D01*
G02X393740Y712620I-334J-219D01*
G01X199102D01*
X184016Y727705D01*
X184065Y727828D01*
G03X181699Y725462I-3947J1581D01*
G01X181822Y725511D01*
X194150Y713183D01*
G02X193867Y712500I-283J-283D01*
G01X164140D01*
G03X162354Y712710I-1140J-2000D01*
G01X162327Y712702D01*
X144173D01*
X144146Y712710D01*
G03X142854I-646J-2210D01*
G01X142827Y712702D01*
X129672D01*
X129471Y712500D01*
X129000D01*
X80000Y663500D01*
Y659514D01*
X52210D01*
X52193Y659696D01*
G03X50060Y657299I-2193J-196D01*
G01X50146Y657301D01*
X50341Y657106D01*
X50225Y656966D01*
G03X53787Y654048I1775J-1466D01*
G01X80000D01*
Y652500D01*
X112000Y620500D01*
Y361500D01*
X108500Y358000D01*
X108750Y357750D01*
Y322250D01*
X124000Y307000D01*
Y293000D01*
X126500Y290500D01*
X146000D01*
X159000Y303500D01*
Y324000D01*
X162013Y327013D01*
G02X162570Y327022I283J-282D01*
G03X165826Y327124I1577J1677D01*
G01X165885Y327188D01*
X166255D01*
X166314Y327124D01*
G03Y330274I1679J1575D01*
G01X166255Y330210D01*
X165885D01*
X165826Y330274D01*
X165824Y330276D01*
G02X165833Y330833I291J274D01*
G01X194998Y359998D01*
X279002D01*
X300000Y339000D01*
X305928D01*
G02X306128Y338254I0J-400D01*
G03X305706Y334050I1301J-2254D01*
G02Y333450I-264J-300D01*
G03X310027Y331648I1723J-1950D01*
G02X310560Y332047I399J22D01*
G03X310337Y336862I869J2453D01*
G02X309804Y337062I-168J363D01*
G03X308730Y338254I-2376J-1061D01*
G02X308930Y339000I200J346D01*
G01X321500D01*
X349500Y311000D01*
Y301500D01*
X273000Y225000D01*
Y169500D01*
X273118Y169382D01*
Y168975D01*
X276500Y165594D01*
Y160233D01*
G02X275795Y159974I-400J0D01*
G03Y150260I-5717J-4857D01*
G02X276500Y150001I305J-259D01*
G01Y113500D01*
X276798Y113202D01*
Y113198D01*
X292370Y97627D01*
X292385Y97592D01*
G03X294011Y96251I2115J908D01*
G02X294263Y95644I-85J-391D01*
G03X296689Y96649I1937J-1244D01*
G02X296437Y97256I85J391D01*
G03X296606Y97571I-1938J1242D01*
G02X297255Y97692I366J-162D01*
G01X297399Y97548D01*
X320399D01*
X325865Y92083D01*
G02X325792Y91459I-283J-283D01*
G03X325296Y91048I1206J-1960D01*
G02X324704I-296J269D01*
G03X321429Y91183I-1704J-1548D01*
G02X320883I-273J292D01*
G03X320880Y87820I-1574J-1680D01*
G02X321426I273J-292D01*
G03X324704Y87952I1574J1680D01*
G02X325296I296J-269D01*
G03X328959Y88292I1704J1548D01*
G02X329583Y88365I341J-210D01*
G01X335149Y82798D01*
X335713D01*
G03X336943Y82016I1787J1452D01*
G01X336997Y82003D01*
X340000Y79000D01*
Y78200D01*
G02X339585Y77800I-400J0D01*
G03Y73200I-85J-2300D01*
G02X340000Y72800I15J-400D01*
G01Y16000D01*
X343500Y12500D01*
X382927D01*
G03X387073I2073J1000D01*
G01X387927D01*
G03X391701Y11948I2074J1000D01*
G01X401552D01*
X402500Y11000D01*
X414323D01*
G02X414464Y10659I0J-200D01*
G01X414107Y10301D01*
X414023Y10302D01*
G03X416302Y8023I-23J-2302D01*
G01X416301Y8107D01*
X419194Y11000D01*
X436323D01*
G02X436645Y10363I0J-400D01*
G03X440802Y9023I1855J-1363D01*
G01X440801Y9107D01*
X441643Y9948D01*
X456643D01*
X457694Y11000D01*
X458000D01*
X496948Y49948D01*
X544143D01*
X545194Y51000D01*
X596212D01*
G02X596447Y50277I0J-400D01*
G03X605403I4478J-6143D01*
G02X605638Y51000I235J323D01*
G01X634204D01*
G02X634439Y50277I0J-400D01*
G03X643395I4478J-6143D01*
G02X643630Y51000I235J323D01*
G01X663500D01*
X676500Y38000D01*
X866500D01*
X871000Y42500D01*
X922500D01*
X994000Y114000D01*
X1030000D01*
X1036500Y107500D01*
Y74000D01*
X1038000Y72500D01*
X1074000D01*
X1075500Y74000D01*
Y108500D01*
X1077000Y110000D01*
X1080500D01*
X1094959Y124459D01*
X1094985Y124473D01*
G03X1095000Y128519I-1091J2027D01*
G01Y213700D01*
X1109000Y227700D01*
Y262500D01*
X1108500Y263000D01*
Y265500D01*
X1113000Y270000D01*
X1130000D01*
X1148000Y252000D01*
Y220000D01*
X1146000Y218000D01*
X1112500D01*
X1108500Y214000D01*
Y6000D01*
X1105501Y3001D01*
X450000D01*
X449999Y3000D01*
X306002D01*
G37*
G36*
G01X45739Y905702D02*
G03X46016Y905270I2064J1019D01*
G01X46130Y905130D01*
X28000Y887000D01*
Y873042D01*
X19958Y865000D01*
X5000D01*
X3500Y866500D01*
Y971500D01*
X16500Y984500D01*
X17000D01*
X17500Y985000D01*
X107000D01*
X112000Y990000D01*
X116254D01*
G03X119746I1746J1500D01*
G01X130000D01*
X133000Y987000D01*
X186500D01*
X188500Y985000D01*
X265000D01*
X280000Y1000000D01*
X538500D01*
X542000Y996500D01*
Y991000D01*
X545500Y987500D01*
X552500D01*
X556500Y991500D01*
Y1012500D01*
X558500Y1014500D01*
X591000D01*
X593500Y1012000D01*
Y989500D01*
X598000Y985000D01*
X716500D01*
X720500Y989000D01*
Y1013000D01*
X722500Y1015000D01*
X740000D01*
X742000Y1013000D01*
Y991000D01*
X746000Y987000D01*
X752000D01*
X756000Y991000D01*
Y1013500D01*
X757000Y1014500D01*
X793000D01*
X793500Y1014000D01*
Y989500D01*
X798500Y984500D01*
X901500D01*
X918500Y967500D01*
Y799000D01*
X916000Y796500D01*
X898000D01*
X844000Y850500D01*
Y862532D01*
G02X844563Y862897I400J0D01*
G03Y867103I937J2103D01*
G02X844000Y867468I-163J365D01*
G01Y874000D01*
X791000Y927000D01*
Y969000D01*
X790892Y969108D01*
Y969897D01*
X778087Y982702D01*
X593298D01*
X591000Y985000D01*
X488406D01*
X484355Y989052D01*
X422055D01*
X417705Y993402D01*
X392995D01*
X392594Y993000D01*
X391462D01*
G03X387538I-1962J-1000D01*
G01X385406D01*
X385012Y993394D01*
X306988D01*
X293795Y980202D01*
X120267D01*
X48844Y908778D01*
X48719Y908832D01*
G03X46461Y908590I-916J-2112D01*
G02X45869Y908738I-233J325D01*
G03X45147Y905850I-2065J-1018D01*
G02X45739Y905702I233J-325D01*
G37*
G36*
G01X296000Y560500D02*
X284500Y572000D01*
X238552D01*
G02X238236Y572646I0J400D01*
G03X234764I-1736J1354D01*
G02X234448Y572000I-316J-246D01*
G01X191968D01*
G02X191603Y572563I0J400D01*
G03X187397I-2103J937D01*
G02X187032Y572000I-365J-163D01*
G01X167500D01*
X165500Y574000D01*
Y583000D01*
X173000Y590500D01*
X175000D01*
G02X175399Y590087I-1J-400D01*
G03X180601I2601J-87D01*
G02X181000Y590500I400J13D01*
G01X297000D01*
X308000Y579500D01*
X316319D01*
G03X319197I1439J1797D01*
G01X361750D01*
X367186Y584936D01*
X367188D01*
X367298Y585046D01*
X367479D01*
X386089Y603656D01*
G02X386761Y603466I283J-283D01*
G03X389534Y606239I2239J534D01*
G02X389344Y606911I93J389D01*
G01X417956Y635523D01*
X418432Y635998D01*
X607429D01*
X607431Y636000D01*
X751000D01*
X753000Y634000D01*
Y633500D01*
X758000Y628500D01*
X760143D01*
X762595Y626048D01*
X892952D01*
X898000Y621000D01*
Y617000D01*
X894500Y613500D01*
X879573D01*
G03X875427I-2073J-1000D01*
G01X835752D01*
X835710Y613644D01*
G03X831353Y613829I-2210J-644D01*
G01X831303Y613702D01*
X696798D01*
X692000Y618500D01*
X430500D01*
X372500Y560500D01*
X296000D01*
G37*
G36*
G01X159500Y613460D02*
X213040Y667000D01*
X328000D01*
X338500Y656500D01*
Y628553D01*
X338498Y628551D01*
Y616500D01*
X319500Y597502D01*
X316449D01*
X316447Y597500D01*
X163500D01*
X159500Y601500D01*
Y613460D01*
G37*
G36*
G01X285500Y118500D02*
X283500Y120500D01*
Y173500D01*
X279522Y177478D01*
Y193022D01*
X281000Y194500D01*
X293500D01*
X295000Y193000D01*
Y142500D01*
X297500Y140000D01*
X325493D01*
X325499Y139806D01*
G03X325578Y139356I1601J49D01*
G01X325588Y139325D01*
Y136826D01*
X325578Y136795D01*
G03X328622I1522J-501D01*
G01X328612Y136826D01*
Y139325D01*
X328622Y139356D01*
G03X328701Y139806I-1522J499D01*
G01X328707Y140000D01*
X339000D01*
X342500Y143500D01*
Y187500D01*
X344500Y189500D01*
X350444D01*
G03X351483Y188793I1287J774D01*
G02X351767Y188206I-67J-394D01*
G03X354470Y188066I1318J-721D01*
G02X354902Y188616I369J155D01*
G03X356465Y189394I237J1483D01*
G01X356522Y189500D01*
X360498D01*
X360538Y189353D01*
G03X363436I1449J394D01*
G01X363476Y189500D01*
X366848D01*
X366889Y189353D01*
G03X369525Y188837I1447J402D01*
G02X370124Y188876I317J-244D01*
G01X370704Y188296D01*
Y188146D01*
X372989Y185862D01*
X373138D01*
X376885Y182115D01*
G02X376839Y181511I-283J-282D01*
G03X376872Y179070I892J-1209D01*
G02X376874Y178415I-228J-328D01*
G03X376491Y178020I869J-1225D01*
G02X375822Y178025I-333J222D01*
G03X373336Y178080I-1262J-815D01*
G02X372689Y178073I-326J232D01*
G03X370238Y178012I-1204J-898D01*
G02X369569Y178017I-333J222D01*
G03X367068Y178049I-1261J-815D01*
G02X366411Y178044I-330J226D01*
G03X363937Y178009I-1225J-869D01*
G02X363274Y178005I-333J222D01*
G03X360774Y177970I-1238J-850D01*
G02X360106Y177964I-336J217D01*
G03X357994Y175900I-1248J-836D01*
G02X357992Y175244I-230J-327D01*
G03X359712Y175238I856J-1234D01*
G02X359714Y175894I230J327D01*
G03X360120Y176313I-855J1235D01*
G02X360788Y176319I336J-217D01*
G03X363285Y176321I1248J836D01*
G02X363948Y176325I333J-222D01*
G03X366426Y176328I1238J850D01*
G02X367083Y176333I330J-226D01*
G03X369555Y176365I1225J869D01*
G02X370224Y176360I333J-222D01*
G03X370660Y175920I1262J814D01*
G02X370654Y175247I-219J-335D01*
G03X372282Y175233I803J-1269D01*
G02X372288Y175906I219J335D01*
G03X372709Y176305I-803J1269D01*
G02X373356Y176312I326J-232D01*
G03X375810Y176378I1204J898D01*
G02X376479Y176373I333J-222D01*
G03X377630Y175690I1262J815D01*
G02X378000Y175291I-30J-399D01*
G01Y173500D01*
X380500Y171000D01*
Y169147D01*
X380374Y169097D01*
G03X379667Y168516I555J-1396D01*
G02X378994Y168517I-336J217D01*
G03X378585Y168939I-1262J-814D01*
G02X378589Y169600I227J329D01*
G03X376897Y169610I-839J1246D01*
G02X376893Y168949I-227J-329D01*
G03X378993Y166888I839J-1246D01*
G02X379666Y166887I336J-217D01*
G03X380374Y166305I1262J814D01*
G01X380500Y166255D01*
Y162858D01*
X380376Y162807D01*
G03X379670Y162213I567J-1391D01*
G02X378992I-339J212D01*
G03Y160621I-1274J-796D01*
G02X379670I339J-212D01*
G03X380376Y160027I1273J797D01*
G01X380500Y159976D01*
Y156500D01*
X379737Y155737D01*
G02X379099Y155836I-283J283D01*
G03X376502Y155958I-1334J-690D01*
G02X375834Y155951I-336J217D01*
G03X375419Y156362I-1244J-841D01*
G02X375415Y157025I222J333D01*
G03X373740Y157015I-845J1242D01*
G02X373744Y156352I-222J-333D01*
G03X375852Y154298I845J-1242D01*
G02X376520Y154305I336J-217D01*
G03X376918Y153905I1245J841D01*
G02X376917Y153244I-225J-330D01*
G03X376296Y152339I842J-1244D01*
G01X376283Y152283D01*
X373433Y149433D01*
G02X372794Y149535I-282J283D01*
G03X370215Y149701I-1339J-681D01*
G02X369558Y149696I-330J226D01*
G03X369186Y150064I-1226J-868D01*
G02X369185Y150722I227J329D01*
G03X369172Y153199I-856J1234D01*
G02X369173Y153862I224J331D01*
G03X369144Y156372I-840J1245D01*
G02X369131Y157036I216J336D01*
G03X369145Y159490I-860J1232D01*
G02X369156Y160148I233J325D01*
G03X369578Y160570I-830J1252D01*
G02X370243Y160572I333J-221D01*
G03X370237Y162241I1246J839D01*
G02X369572Y162239I-333J221D01*
G03X369147Y162658I-1246J-839D01*
G02Y163328I218J335D01*
G03X369187Y165815I-822J1257D01*
G02X369189Y166471I230J327D01*
G03X369582Y166870I-855J1235D01*
G02X370241Y166877I332J-223D01*
G03X370222Y168577I1229J864D01*
G02X369563Y168570I-332J223D01*
G03X369181Y168946I-1228J-865D01*
G02X369176Y169603I226J330D01*
G03X367088Y171705I-867J1227D01*
G02X366432Y171715I-325J234D01*
G03X363942Y171718I-1246J-839D01*
G02X363280I-331J224D01*
G03Y170034I-1244J-842D01*
G02X363942I331J-224D01*
G03X366407Y170001I1244J842D01*
G02X367063Y169991I325J-234D01*
G03X367462Y169590I1245J840D01*
G02X367467Y168933I-226J-330D01*
G03X367472Y166476I867J-1227D01*
G02X367470Y165820I-230J-327D01*
G03X367066Y165405I854J-1236D01*
G02X366400Y165398I-335J218D01*
G03X364325Y163304I-1242J-844D01*
G02X364329Y162641I-221J-333D01*
G03X363937Y162249I848J-1240D01*
G02X363276Y162250I-330J226D01*
G03X363273Y160557I-1242J-844D01*
G02X363934Y160556I330J-226D01*
G03X366420Y160558I1242J844D01*
G02X367082I331J-224D01*
G03X367452Y160178I1244J841D01*
G02X367441Y159520I-233J-325D01*
G03X367460Y157003I830J-1252D01*
G02X367473Y156339I-216J-336D01*
G03X367070Y155921I860J-1232D01*
G02X366399Y155919I-336J216D01*
G03X363909Y155960I-1259J-819D01*
G02X363250Y155964I-328J229D01*
G03X363240Y154259I-1241J-845D01*
G02X363899Y154255I328J-229D01*
G03X364305Y153851I1243J843D01*
G02X364306Y153187I-222J-332D01*
G03X366406Y151125I840J-1245D01*
G02X367076Y151128I336J-217D01*
G03X367476Y150719I1254J827D01*
G02X367477Y150061I-227J-329D01*
G03X367482Y147589I856J-1234D01*
G02X367478Y146928I-227J-329D01*
G03X367487Y144426I836J-1248D01*
G02Y143759I-221J-334D01*
G03X367085Y143368I828J-1253D01*
G02X366426Y143374I-327J230D01*
G03X363926Y143356I-1244J-842D01*
G02X363259Y143353I-334J219D01*
G03X363265Y141696I-1250J-833D01*
G02X363932Y141699I334J-219D01*
G03X364476Y141206I1250J833D01*
G02X364571Y140571I-188J-353D01*
G01X363000Y139000D01*
Y127500D01*
X354000Y118500D01*
X348522D01*
G02X348202Y119140I0J400D01*
G03X345798I-1202J900D01*
G02X345478Y118500I-320J-240D01*
G01X341522D01*
G02X341202Y119140I0J400D01*
G03X338798I-1202J900D01*
G02X338478Y118500I-320J-240D01*
G01X336112D01*
X336092Y118678D01*
G03X332908I-1592J-178D01*
G01X332888Y118500D01*
X332309D01*
X332295Y118684D01*
G03X328266Y120014I-2295J-184D01*
G02X327663I-301J263D01*
G03X324042Y119819I-1734J-1514D01*
G02X323387I-328J229D01*
G03X319205Y118684I-1887J-1319D01*
G01X319191Y118500D01*
X285500D01*
G37*
G36*
G01X333206Y92794D02*
X325783Y100217D01*
X325910Y100359D01*
G03X321938Y101474I-1710J1541D01*
G02X321545Y101000I-393J-74D01*
G01X319809D01*
X319795Y101184D01*
G03X316652Y103140I-2295J-184D01*
G02X316134Y103362I-147J372D01*
G03X311897Y101563I-2134J-862D01*
G02X311532Y101000I-365J-163D01*
G01X298053D01*
X295000Y104053D01*
Y116000D01*
X296000Y117000D01*
X319754D01*
G03X323246I1746J1500D01*
G01X324183D01*
G03X327618Y116936I1746J1500D01*
G01X327677Y117000D01*
X328252D01*
X328311Y116936D01*
G03X331746Y117000I1689J1564D01*
G01X333936D01*
X333969Y116989D01*
G03X335031I531J1511D01*
G01X335064Y117000D01*
X353500D01*
X401500Y69000D01*
Y26753D01*
G03Y20491I1453J-3131D01*
G01Y19500D01*
X400500Y18500D01*
X376000D01*
X372000Y22500D01*
Y49336D01*
G03Y52664I-2000J1664D01*
G01Y53836D01*
G03X371723Y57450I-2000J1664D01*
G02Y58050I264J300D01*
G03X367430Y59593I-1723J1950D01*
G02X366752Y59248I-395J-62D01*
G01X364372Y61628D01*
G02X364368Y62189I283J283D01*
G03X360689Y65868I-1868J1811D01*
G02X360128Y65872I-278J287D01*
G01X339384Y86616D01*
G02X339667Y87298I283J282D01*
G01X341449D01*
G03Y90702I1551J1702D01*
G01X338205D01*
X336705Y92202D01*
X334551D01*
G03X333275Y92786I-1551J-1702D01*
G01X333206Y92794D01*
G37*
G36*
G01X381500Y865000D02*
X375000Y871500D01*
X365140D01*
G03X362860I-1140J-2000D01*
G01X345211D01*
X339759Y876952D01*
X337048D01*
X336000Y878000D01*
Y947059D01*
G02X336538Y947434I400J0D01*
G03X339501Y949560I762J2066D01*
G01X339499Y949646D01*
X340401Y950548D01*
X386905D01*
G03X390327Y953287I1845J1202D01*
G02X390300Y953815I286J279D01*
G03X386713Y956702I-1800J1435D01*
G01X337351D01*
X336000Y958053D01*
Y963500D01*
X337000Y964500D01*
X376968D01*
G02X377357Y964008I0J-400D01*
G03X381643I2143J-508D01*
G02X382032Y964500I389J92D01*
G01X413300D01*
G02X413700Y964085I0J-400D01*
G03X414716Y962089I2300J-86D01*
G02X414723Y961430I-223J-332D01*
G03X413748Y959675I1323J-1884D01*
G02X413371Y959298I-400J23D01*
G03X411203Y957157I129J-2298D01*
G02X410759Y956787I-399J27D01*
G03X411364Y952366I-259J-2287D01*
G02X411914Y952010I150J-370D01*
G03X412625Y950424I2301J79D01*
G02X412667Y949893I-276J-289D01*
G03X416204Y946952I1833J-1393D01*
G02X416796I296J-269D01*
G03X420095Y946840I1704J1548D01*
G02X420627Y946859I277J-289D01*
G03X420503Y950290I1471J1771D01*
G02X419971Y950271I-277J289D01*
G03X416796Y950048I-1471J-1771D01*
G02X416204I-296J269D01*
G03X416090Y950165I-1705J-1547D01*
G02X416048Y950696I276J289D01*
G03X414812Y954312I-1833J1393D01*
G02X414706Y955039I104J386D01*
G03X415798Y956871I-1206J1961D01*
G02X416175Y957248I400J-23D01*
G03X417330Y961457I-129J2298D01*
G02X417323Y962116I223J332D01*
G03X417704Y962452I-1323J1884D01*
G02X418296I296J-269D01*
G03X422300Y964085I1704J1548D01*
G02X422700Y964500I400J15D01*
G01X470000D01*
X477500Y957000D01*
X750480D01*
X780000Y927480D01*
Y911000D01*
X777500Y908500D01*
X657222D01*
X657196Y908507D01*
G03X655804I-696J-2507D01*
G01X655778Y908500D01*
X485573D01*
G03X481427I-2073J-1000D01*
G01X421500D01*
X406500Y893500D01*
Y878000D01*
X398000Y869500D01*
X394500D01*
X392500Y867500D01*
Y866000D01*
X391500Y865000D01*
X381500D01*
G37*
G36*
G01X415950Y640452D02*
X377998Y602500D01*
X350000D01*
X347000Y605500D01*
Y625500D01*
X383998Y662498D01*
X384255D01*
X391737Y669980D01*
X601020D01*
X603000Y668000D01*
Y642500D01*
X601500Y641000D01*
X416500D01*
X415952Y640452D01*
X415950D01*
G37*
G36*
G01X377500Y125500D02*
X375000Y128000D01*
Y134765D01*
X375130Y134813D01*
G03X375434Y137474I-524J1408D01*
G02X375433Y138140I221J333D01*
G03X375846Y138552I-834J1249D01*
G02X376509Y138554I332J-223D01*
G03X378612Y140630I1241J846D01*
G02X378613Y141286I230J328D01*
G03X379001Y141678I-855J1235D01*
G02X379663I331J-224D01*
G03X382150Y141677I1244J842D01*
G02X382813I332J-224D01*
G03X383199Y141287I1242J844D01*
G02X383191Y140624I-228J-329D01*
G03X385266Y138533I828J-1253D01*
G02X385929Y138534I332J-223D01*
G03X388031Y140609I1244J842D01*
G02X388038Y141270I229J328D01*
G03X388449Y141677I-831J1251D01*
G02X389112I331J-224D01*
G03X391599Y141678I1243J843D01*
G02X392261I331J-224D01*
G03X392683Y141263I1244J842D01*
G02X392684Y140594I-219J-335D01*
G03X394769Y138520I826J-1254D01*
G02X395436Y138525I335J-218D01*
G03X397931Y138526I1247J837D01*
G02X398594Y138529I333J-222D01*
G03X401065Y138513I1241J846D01*
G02X401720Y138512I327J-230D01*
G03X404197Y138528I1233J858D01*
G02X404859Y138529I331J-224D01*
G03X406946Y140614I1244J842D01*
G02Y141277I224J331D01*
G03X404860Y143363I-843J1243D01*
G02X404197I-332J224D01*
G03X401703Y143352I-1243J-843D01*
G02X401036Y143354I-333J221D01*
G03X400637Y143764I-1256J-824D01*
G02X400642Y144424I229J328D01*
G03X398946Y144437I-838J1246D01*
G02X398941Y143777I-229J-328D01*
G03X398542Y143384I836J-1248D01*
G02X397886Y143381I-329J227D01*
G03X395411Y143362I-1231J-861D01*
G02X394749I-331J224D01*
G03X394347Y143764I-1244J-842D01*
G02Y144426I224J331D01*
G03X392663I-842J1244D01*
G02Y143764I-224J-331D01*
G03X392261Y143362I842J-1244D01*
G02X391599I-331J224D01*
G03X389112Y143363I-1244J-842D01*
G02X388449I-332J224D01*
G03X388048Y143764I-1243J-842D01*
G02Y144426I224J331D01*
G03X386364I-842J1244D01*
G02Y143764I-224J-331D01*
G03X385962Y143362I842J-1244D01*
G02X385300I-331J224D01*
G03X382813Y143363I-1244J-842D01*
G02X382150I-332J224D01*
G03X379663Y143362I-1243J-843D01*
G02X379001I-331J224D01*
G03X376513I-1244J-842D01*
G02X375851I-331J224D01*
G03X375130Y143928I-1244J-842D01*
G01X375000Y143976D01*
Y150000D01*
X375500Y150500D01*
X376388D01*
G02X376682Y149829I0J-400D01*
G03X379008Y147937I1105J-1017D01*
G02X379660Y147934I325J-233D01*
G03X381984Y149826I1228J865D01*
G02X382275Y150500I291J274D01*
G01X383775D01*
X383794Y150496D01*
G03X384392I299J1472D01*
G01X384411Y150500D01*
X390149D01*
X390161Y150499D01*
G03X390517I178J1491D01*
G01X390529Y150500D01*
X393329D01*
X393341Y150499D01*
G03X393697I178J1491D01*
G01X393709Y150500D01*
X396449D01*
X396461Y150499D01*
G03X396817I178J1491D01*
G01X396829Y150500D01*
X399426D01*
X399451Y150494D01*
G03X400187I368J1456D01*
G01X400212Y150500D01*
X402545D01*
X402570Y150494D01*
G03X403306I368J1456D01*
G01X403331Y150500D01*
X404733D01*
G02X405026Y149827I0J-400D01*
G03X407224I1099J-1023D01*
G02X407517Y150500I293J273D01*
G01X408500D01*
X411500Y147500D01*
Y143720D01*
G03Y141320I903J-1200D01*
G01Y137390D01*
G03Y135030I929J-1180D01*
G01Y127000D01*
X410000Y125500D01*
X377500D01*
G37*
G36*
G01X398500Y451000D02*
X391000Y458500D01*
X376500D01*
X367500Y467500D01*
Y480526D01*
X367646Y480567D01*
G03X368589Y484469I-624J2216D01*
G02X368579Y485045I272J293D01*
G01X422534Y539000D01*
X513946D01*
X513960Y538814D01*
G03X515512Y536616I2595J186D01*
G02Y535884I-161J-366D01*
G03X515115Y531333I1043J-2384D01*
G02Y530667I-222J-333D01*
G03X518505Y526777I1440J-2167D01*
G02X519105I300J-264D01*
G03X519309Y526571I1948J1725D01*
G02X519302Y525971I-268J-297D01*
G03X523309Y522800I1698J-1971D01*
G02X523975Y522866I355J-185D01*
G03X527723Y526450I2025J1634D01*
G02Y527050I264J300D01*
G03X527746Y530929I-1723J1950D01*
G02X527753Y531529I268J297D01*
G03X527495Y535667I-1698J1971D01*
G02Y536333I222J333D01*
G03X528656Y538587I-1440J2168D01*
G02X529055Y539000I400J13D01*
G01X685500D01*
X754000Y470500D01*
Y455613D01*
X749888Y451502D01*
X727672D01*
G02X727277Y451960I0J400D01*
G03X722723I-2277J340D01*
G02X722328Y451502I-395J-58D01*
G01X642637D01*
G03X639754Y451000I-1137J-2002D01*
G01X620209D01*
X620208Y451002D01*
X447292D01*
X447291Y451000D01*
X398500D01*
G37*
G36*
G01X966500Y212500D02*
G02X966087Y212101I-400J1D01*
G03Y206899I-87J-2601D01*
G02X966500Y206500I13J-400D01*
G01Y192500D01*
X961473Y187473D01*
G02X960792Y187718I-283J283D01*
G03X959982Y189261I-2292J-219D01*
G02X959907Y189789I258J306D01*
G03X956508Y189303I-1917J1275D01*
G02X956583Y188775I-258J-306D01*
G03X958281Y185208I1917J-1275D01*
G02X958526Y184527I-38J-398D01*
G01X946448Y172450D01*
Y172448D01*
X903000Y129000D01*
X836500D01*
X806000Y98500D01*
X750000D01*
X744500Y104000D01*
Y140000D01*
X735500Y149000D01*
X707000D01*
X680500Y122500D01*
X665500D01*
X648500Y105500D01*
X573000D01*
X535452Y67952D01*
X470821D01*
X437369Y34500D01*
X405500D01*
X403500Y36500D01*
Y91000D01*
X427000Y114500D01*
X466532D01*
G02X466897Y113937I0J-400D01*
G03X470835Y111610I2103J-937D01*
G02X471425Y111661I318J-242D01*
G03X475202Y113989I1565J1688D01*
G02X475586Y114500I384J111D01*
G01X479500D01*
X485000Y109000D01*
X520500D01*
X568000Y156500D01*
X593500D01*
X620398Y183398D01*
X706719D01*
G02X707002Y182716I0J-400D01*
G01X682798Y158512D01*
Y151887D01*
G03X687202I2202J-1387D01*
G01Y156688D01*
X708866Y178352D01*
G02X709497Y178266I283J-283D01*
G03X712411Y181514I2003J1134D01*
G02X712190Y182007I159J367D01*
G03X712287Y182953I-2090J692D01*
G02X712684Y183398I397J45D01*
G01X718113D01*
G03Y187802I1387J2202D01*
G01X625767D01*
G02X625484Y188484I0J400D01*
G01X663000Y226000D01*
X867234D01*
X867249Y225816D01*
G03X870094Y228235I2295J184D01*
G02X869907Y228907I95J389D01*
G01X906000Y265000D01*
Y321500D01*
X927500Y343000D01*
X957500D01*
X968500Y354000D01*
X1006000D01*
X1017000Y343000D01*
Y324500D01*
X966500Y274000D01*
Y263135D01*
G02X966011Y262745I-400J0D01*
G03X963782Y258968I-511J-2245D01*
G02X963486Y258302I-299J-266D01*
G03X961815Y254432I14J-2302D01*
G02X961593Y253766I-293J-272D01*
G03X963685Y253068I406J-2266D01*
G02X963907Y253734I293J272D01*
G03X965218Y257532I-407J2266D01*
G02X965514Y258198I299J266D01*
G03X966011Y258255I-12J2302D01*
G02X966500Y257865I89J-390D01*
G01Y212500D01*
G37*
G36*
G01X446985Y312910D02*
X445078Y314817D01*
G02X445219Y315158I141J141D01*
G01X445395D01*
G03Y320062I0J2452D01*
G01X442835D01*
Y320927D01*
G03Y321073I-1500J73D01*
G01Y328534D01*
G02X443457Y328867I400J0D01*
G03Y331367I833J1250D01*
G02X442835Y331700I-222J333D01*
G01Y332631D01*
G02X443513Y332919I400J0D01*
G03Y335081I1042J1081D01*
G02X442835Y335369I-278J288D01*
G01Y336408D01*
G02X443457Y336741I400J0D01*
G03Y339241I833J1250D01*
G02X442835Y339574I-222J333D01*
G01Y340345D01*
G02X443457Y340678I400J0D01*
G03Y343178I833J1250D01*
G02X442835Y343511I-222J333D01*
G01Y346950D01*
X443275Y347390D01*
X445500D01*
X445890Y347000D01*
X446000D01*
X446500Y346500D01*
Y346073D01*
G03Y345927I1500J-73D01*
G01Y344000D01*
X447000Y343500D01*
X447420D01*
Y343199D01*
X447338Y343139D01*
G03X449410Y342854I889J-1211D01*
G02X449725Y343500I315J246D01*
G01X454605D01*
G02X454920Y342854I0J-400D01*
G03X456992Y343139I1183J-926D01*
G01X456910Y343199D01*
Y343500D01*
X457575D01*
X458575Y342500D01*
Y342260D01*
X458571Y342239D01*
G03Y341617I1469J-311D01*
G01X458575Y341596D01*
Y338323D01*
X458571Y338302D01*
G03Y337680I1469J-311D01*
G01X458575Y337659D01*
Y334386D01*
X458571Y334365D01*
G03Y333743I1469J-311D01*
G01X458575Y333722D01*
Y330449D01*
X458571Y330428D01*
G03Y329806I1469J-311D01*
G01X458575Y329785D01*
Y321500D01*
X449985Y312910D01*
X446985D01*
G37*
G36*
G01X435500Y347500D02*
X433000Y350000D01*
Y360199D01*
X433115Y360252D01*
G03Y362974I-636J1361D01*
G01X433000Y363027D01*
Y368073D01*
X433115Y368126D01*
G03Y370848I-636J1361D01*
G01X433000Y370901D01*
Y375949D01*
X433115Y376002D01*
G03Y378724I-636J1361D01*
G01X433000Y378777D01*
Y379886D01*
X433115Y379939D01*
G03Y382661I-636J1361D01*
G01X433000Y382714D01*
Y383823D01*
X433115Y383876D01*
G03Y386598I-636J1361D01*
G01X433000Y386651D01*
Y387760D01*
X433115Y387813D01*
G03Y390535I-636J1361D01*
G01X433000Y390588D01*
Y391697D01*
X433115Y391750D01*
G03Y394472I-636J1361D01*
G01X433000Y394525D01*
Y395634D01*
X433115Y395687D01*
G03Y398409I-636J1361D01*
G01X433000Y398462D01*
Y399571D01*
X433115Y399624D01*
G03Y402346I-636J1361D01*
G01X433000Y402399D01*
Y403508D01*
X433115Y403561D01*
G03Y406283I-636J1361D01*
G01X433000Y406336D01*
Y407445D01*
X433115Y407498D01*
G03Y410220I-636J1361D01*
G01X433000Y410273D01*
Y411382D01*
X433115Y411435D01*
G03Y414157I-636J1361D01*
G01X433000Y414210D01*
Y424917D01*
G02X433678Y425204I400J0D01*
G03Y427362I1045J1079D01*
G02X433000Y427649I-278J287D01*
G01Y436000D01*
X447500Y450500D01*
X562278D01*
X562304Y450493D01*
G03X563696I696J2507D01*
G01X563722Y450500D01*
X566778D01*
X566804Y450493D01*
G03X568196I696J2507D01*
G01X568222Y450500D01*
X620000D01*
X631179Y439321D01*
G02X631110Y438700I-283J-283D01*
G03X631060Y434333I1390J-2200D01*
G02Y433667I-222J-333D01*
G03X632007Y428945I1440J-2167D01*
G02X632273Y428346I-76J-393D01*
G03X636754Y428300I2227J-1346D01*
G02X637087Y428899I347J199D01*
G03X638440Y433667I-87J2601D01*
G02Y434333I222J333D01*
G03X639549Y437020I-1440J2167D01*
G02X639941Y437500I392J80D01*
G01X657857D01*
G02X658248Y437017I0J-400D01*
G03X662752I2252J-479D01*
G02X663143Y437500I391J83D01*
G01X771500D01*
X774500Y434500D01*
Y370500D01*
X770500Y366500D01*
X710626D01*
G03X706374I-2126J-1500D01*
G01X676000D01*
X672000Y370500D01*
X666664D01*
G03X663336I-1664J-2000D01*
G01X661164D01*
G03X657836I-1664J-2000D01*
G01X655164D01*
G03X651836I-1664J-2000D01*
G01X649164D01*
G03X645836I-1664J-2000D01*
G01X643664D01*
G03X640336I-1664J-2000D01*
G01X637598D01*
G03X637402I-98J-2600D01*
G01X632164D01*
G03X628836I-1664J-2000D01*
G01X627500D01*
X623000Y366000D01*
X578097D01*
X571356Y372740D01*
X562737D01*
X561188Y371196D01*
X560944Y370952D01*
X548679D01*
X548641Y370968D01*
G03X546748Y370500I-641J-1468D01*
G01X507342D01*
G02X506959Y371017I0J400D01*
G03X504087I-1436J439D01*
G02X503704Y370500I-383J-117D01*
G01X496807D01*
G03X494303I-1252J-1000D01*
G01X492645D01*
G03X490427I-1109J-1013D01*
G01X488708D01*
G03X486498I-1105J-1017D01*
G01X484709D01*
G03X482657I-1026J-1097D01*
G01X480834D01*
G03X478654Y368434I-1109J-1013D01*
G02X478653Y368153I-143J-140D01*
G01X474500Y364000D01*
Y362386D01*
G03Y360840I1288J-773D01*
G01Y358449D01*
G03Y356903I1288J-773D01*
G01Y350575D01*
G03X474326Y349459I1288J-772D01*
G01X474351Y349351D01*
X472500Y347500D01*
X469388D01*
G03X468824Y347869I-1473J-1636D01*
G02X468764Y348563I166J364D01*
G03X467064I-850J1239D01*
G02X467004Y347869I-226J-330D01*
G03X466440Y347500I909J-2005D01*
G01X448073D01*
G03X447927I-73J-1500D01*
G01X446209D01*
X446208Y347502D01*
X446098D01*
X445708Y347892D01*
X443067D01*
X442676Y347500D01*
X435500D01*
G37*
G36*
G01X507000Y865502D02*
X501050Y871452D01*
X501048D01*
X492000Y880500D01*
Y887000D01*
X492828Y887828D01*
X506672D01*
X514500Y880000D01*
X515447D01*
X515449Y879998D01*
X610502D01*
X612500Y878000D01*
Y866500D01*
X611502Y865502D01*
X507000D01*
G37*
G36*
G01X584001Y251500D02*
X583000Y252501D01*
Y258444D01*
X583028Y258472D01*
Y259938D01*
G03Y260118I-2200J90D01*
G01Y265472D01*
X583055Y265500D01*
Y283300D01*
X583128Y283372D01*
Y284628D01*
X585000Y286500D01*
X861755D01*
X863755Y288500D01*
Y291300D01*
X862802Y292253D01*
G03X861952Y293108I-2764J-1897D01*
G01X861937Y293118D01*
X859355Y295700D01*
Y297413D01*
X859361Y297436D01*
G03Y299024I-3257J794D01*
G01X859355Y299047D01*
Y307253D01*
X859361Y307276D01*
G03Y308864I-3257J794D01*
G01X859355Y308887D01*
Y309855D01*
X863500Y314000D01*
Y320500D01*
X866000Y323000D01*
X879500D01*
X882355Y320145D01*
Y299622D01*
G02X881672Y299340I-400J0D01*
G01X881330Y299682D01*
X874870D01*
G03Y296778I-3021J-1452D01*
G01X880128D01*
X882355Y294551D01*
Y268500D01*
X865355Y251500D01*
X781612D01*
G03X778388I-1612J-1500D01*
G01X584001D01*
G37*
G36*
G01X590000Y350000D02*
X593000Y353000D01*
X717500D01*
X723500Y347000D01*
Y329500D01*
X720000Y326000D01*
X593000D01*
X590000Y329000D01*
Y350000D01*
G37*
G36*
G01X598000Y774500D02*
X597000Y775500D01*
Y786500D01*
X598000Y787500D01*
X860358D01*
X861500Y786358D01*
Y776000D01*
X860000Y774500D01*
X725869D01*
G02X725469Y774912I0J400D01*
G03X720867I-2301J72D01*
G02X720467Y774500I-400J-12D01*
G01X717522D01*
G02X717166Y775083I0J400D01*
G03X713070I-2048J1051D01*
G02X712714Y774500I-356J-183D01*
G01X679573D01*
G03X675427I-2073J-1000D01*
G01X598000D01*
G37*
G36*
G01X876500Y45000D02*
X870847Y50653D01*
X873991Y53797D01*
X874070Y53799D01*
G03X871799Y56070I-70J2201D01*
G01X871797Y55991D01*
X868306Y52500D01*
X865160D01*
G02X864877Y53183I0J400D01*
G01X871643Y59948D01*
X871935D01*
X871993Y59894D01*
G03X871937Y63052I1507J1606D01*
G01X870357D01*
X859806Y52500D01*
X853160D01*
G02X852877Y53183I0J400D01*
G01X862491Y62797D01*
X862570Y62799D01*
G03X864270Y66310I-70J2201D01*
G02X864591Y66948I321J238D01*
G01X871299D01*
G03Y70052I1701J1552D01*
G01X861857D01*
X844306Y52500D01*
X747892D01*
G03X747708I-92J-2300D01*
G01X731449D01*
G02X731081Y53058I0J400D01*
G03X726851I-2115J908D01*
G02X726483Y52500I-368J-158D01*
G01X702248D01*
X666250Y88498D01*
Y90061D01*
X666248Y90063D01*
Y101532D01*
G02X666811Y101897I400J0D01*
G03Y106103I937J2103D01*
G02X666248Y106468I-163J365D01*
G01Y116800D01*
X669448Y120000D01*
X681248D01*
X708248Y147000D01*
X733248D01*
X742248Y138000D01*
Y99752D01*
X746000Y96000D01*
X758132D01*
G02X758497Y95437I0J-400D01*
G03X762703I2103J-937D01*
G02X763068Y96000I365J163D01*
G01X807500D01*
X838000Y126500D01*
X943000D01*
X1048000Y231500D01*
X1057500D01*
X1059000Y230000D01*
Y212640D01*
G03X1058976Y210404I2000J-1140D01*
G01X1059000Y210359D01*
Y209573D01*
G03Y205427I1000J-2073D01*
G01Y195700D01*
G02X1058289Y195448I-400J0D01*
G03Y192552I-1789J-1448D01*
G02X1059000Y192300I311J-252D01*
G01Y186000D01*
X1014000Y141000D01*
Y136000D01*
X923000Y45000D01*
X876500D01*
G37*
G36*
G01X881784Y445216D02*
X877000Y450000D01*
X871640D01*
G03X869360I-1140J-2000D01*
G01X790797D01*
X790748Y450128D01*
G03X790358Y450786I-2148J-828D01*
G02X790388Y451333I306J258D01*
G03X787139Y454593I-1588J1667D01*
G02X786561I-289J277D01*
G03X784793Y455300I-1662J-1593D01*
G01X784705Y455295D01*
X781133Y458867D01*
X781118Y458903D01*
G03X777449Y459702I-2118J-903D01*
G01X763795D01*
X763594Y459500D01*
X758500D01*
X755500Y462500D01*
Y479000D01*
X757500Y481000D01*
X769865D01*
G02X770184Y480360I-1J-400D01*
G03X773660Y477356I1840J-1384D01*
G02X774248Y477334I284J-281D01*
G03X777738Y480338I1752J1494D01*
G02X778040Y481000I302J262D01*
G01X778387D01*
X781588Y477798D01*
X781702D01*
X782000Y477500D01*
X794328D01*
G03X797820I1746J1500D01*
G01X806500D01*
X812368Y471632D01*
G03X816189Y470936I2132J868D01*
G01X816248Y471000D01*
X816498D01*
X816558Y470929D01*
G03X820718Y470298I2442J2071D01*
G01X887326D01*
X888028Y471000D01*
X894500D01*
X916129Y449371D01*
X916123Y449281D01*
G03X918571Y446833I2297J-151D01*
G01X918661Y446839D01*
X934500Y431000D01*
X993500D01*
X995500Y429000D01*
Y388000D01*
X993000Y385500D01*
X931500D01*
X897000Y420000D01*
Y430000D01*
X886776Y440224D01*
G02X886947Y440891I283J283D01*
G03X887834Y441383I-646J2210D01*
G02X888366I266J-298D01*
G03X891476Y441422I1534J1717D01*
G02X892024I274J-291D01*
G03Y444778I1576J1678D01*
G02X891476I-274J291D01*
G03X888366Y444817I-1576J-1678D01*
G02X887834I-266J298D01*
G03X884766I-1534J-1717D01*
G02X884234I-266J298D01*
G03X881904Y445260I-1534J-1717D01*
G01X881784Y445216D01*
G37*
G36*
G01X1102088Y509298D02*
X1118888Y492498D01*
X1178612D01*
X1181113Y495000D01*
X1195500D01*
X1197000Y493500D01*
Y485053D01*
X1191447Y479500D01*
X1188000D01*
X1181000Y472500D01*
X1108000D01*
X1094000Y486500D01*
X1070315D01*
G02X1070017Y487166I0J400D01*
G03X1066583I-1717J1534D01*
G02X1066285Y486500I-298J-266D01*
G01X1030500D01*
X1024179Y492821D01*
X1024169Y492883D01*
G03X1022383Y494669I-2169J-383D01*
G01X1022321Y494679D01*
X1021750Y495250D01*
X838250D01*
X834500Y499000D01*
Y516000D01*
X837500Y519000D01*
X919500D01*
X921500Y521000D01*
X924522D01*
X925023Y520498D01*
X999800D01*
G02X1000200Y520084I0J-400D01*
G03X1004800I2300J-84D01*
G02X1005200Y520498I400J14D01*
G01X1012588D01*
X1013088Y519998D01*
X1013800D01*
G02X1014200Y519584I0J-400D01*
G03X1018800I2300J-84D01*
G02X1019200Y519998I400J14D01*
G01X1063888D01*
X1074588Y509298D01*
X1086328D01*
G02X1086723Y508840I0J-400D01*
G03X1091277I2277J-340D01*
G02X1091672Y509298I395J58D01*
G01X1102088D01*
G37*
G36*
G01X1211499Y3001D02*
X1210000Y4500D01*
Y141000D01*
X1214500Y145500D01*
X1333000D01*
X1336000Y148500D01*
Y268174D01*
G02X1336415Y268574I400J0D01*
G03X1338773Y271240I85J2300D01*
G02X1339143Y271702I395J63D01*
G03X1336727Y273634I-143J2298D01*
G02X1336357Y273172I-395J-63D01*
G03X1336224Y273159I157J-2297D01*
G01X1336212Y273158D01*
X1336000D01*
Y301500D01*
X1338138Y303638D01*
X1338273Y303552D01*
G03X1341358Y306858I1226J1948D01*
G01X1369500Y335000D01*
Y353865D01*
G02X1369989Y354255I400J0D01*
G03Y358745I511J2245D01*
G02X1369500Y359135I-89J390D01*
G01Y363000D01*
X1308500Y424000D01*
Y437000D01*
X1314750Y443250D01*
Y493750D01*
X1352397Y531397D01*
X1352475Y531399D01*
G03X1352675Y535785I-74J2201D01*
G01X1352500Y535807D01*
Y612000D01*
X1338250Y626250D01*
Y663197D01*
X1338952Y663899D01*
Y844419D01*
X1338250Y845121D01*
Y845250D01*
X1316000Y867500D01*
X1274500D01*
X1176750Y965250D01*
X1029250D01*
X999600Y935600D01*
X993400D01*
X991800Y937200D01*
Y966900D01*
X1010000Y985100D01*
X1380400D01*
X1397000Y968500D01*
Y492000D01*
X1395500Y490500D01*
X1352500D01*
X1350500Y488500D01*
Y470000D01*
X1351840Y468660D01*
G02X1351845Y468100I-283J-283D01*
G03X1355100Y464845I1655J-1600D01*
G02X1355660Y464840I277J-288D01*
G01X1360448Y460052D01*
X1360393Y459927D01*
G03X1363427Y456893I2107J-927D01*
G01X1363552Y456948D01*
X1364500Y456000D01*
X1364801D01*
X1377798Y443002D01*
Y394002D01*
X1378000Y393801D01*
Y393000D01*
X1380000Y391000D01*
Y357500D01*
X1378000Y355500D01*
Y355199D01*
X1377798Y354998D01*
Y315551D01*
G03Y312449I1702J-1551D01*
G01Y299298D01*
X1360000Y281500D01*
Y252000D01*
X1361500Y250500D01*
X1394000D01*
X1397000Y247500D01*
Y98217D01*
G02X1396242Y98039I-400J0D01*
G03Y94481I-3585J-1779D01*
G02X1397000Y94303I358J-178D01*
G01Y80501D01*
G02X1396242Y80323I-400J0D01*
G03Y76765I-3585J-1779D01*
G02X1397000Y76587I358J-178D01*
G01Y61996D01*
G02X1396242Y61818I-400J0D01*
G03Y58260I-3585J-1779D01*
G02X1397000Y58082I358J-178D01*
G01Y44280D01*
G02X1396242Y44102I-400J0D01*
G03Y40544I-3585J-1779D01*
G02X1397000Y40366I358J-178D01*
G01Y4501D01*
X1395500Y3001D01*
X1211499D01*
G37*
G36*
G01X1040500Y74500D02*
X1039000Y76000D01*
Y107000D01*
X1022552Y123448D01*
X1022607Y123573D01*
G03X1019451Y126549I-2107J927D01*
G01X1018000Y128000D01*
Y141000D01*
X1031229Y154229D01*
G02X1031880Y154102I283J-283D01*
G03X1034898Y157120I2120J898D01*
G02X1034771Y157771I156J368D01*
G01X1036527Y159527D01*
G02X1037208Y159282I283J-283D01*
G03X1038046Y157715I2292J218D01*
G02X1038042Y157091I-252J-310D01*
G03X1038079Y153449I1426J-1807D01*
G02X1038083Y152814I-242J-319D01*
G03X1041802Y150986I1417J-1814D01*
G02X1042468Y151282I400J-3D01*
G03X1045275Y154917I1532J1718D01*
G02Y155583I221J333D01*
G03X1042468Y159218I-1275J1917D01*
G02X1041802Y159514I-266J299D01*
G03X1039718Y161792I-2302J-14D01*
G02X1039473Y162473I38J398D01*
G01X1062000Y185000D01*
Y206360D01*
G03X1062024Y208596I-2000J1140D01*
G01X1062000Y208641D01*
Y209427D01*
G03Y213573I-1000J2073D01*
G01Y280374D01*
G03Y284626I-1500J2126D01*
G01Y289211D01*
G03Y291989I-2200J1389D01*
G01Y293664D01*
G03Y296736I-2100J1536D01*
G01Y300957D01*
G03Y305343I-1400J2193D01*
G01Y393483D01*
G03X1062655Y396742I-1234J1943D01*
G02X1062719Y397271I328J229D01*
G03X1062000Y401159I-1519J1730D01*
G01Y437980D01*
X1066520Y442500D01*
X1094500D01*
X1101000Y436000D01*
Y266112D01*
G03Y262888I1500J-1612D01*
G01Y251962D01*
G03Y248038I1000J-1962D01*
G01Y234000D01*
X1084500Y217500D01*
Y204802D01*
G03Y200198I0J-2302D01*
G01Y194626D01*
G03Y190374I1500J-2126D01*
G01Y189626D01*
G03Y185374I1500J-2126D01*
G01Y160924D01*
X1084361Y160879D01*
G03X1083222Y156653I789J-2479D01*
G02X1083200Y156094I-297J-268D01*
G03X1082780Y155579I1790J-1889D01*
G02X1082182Y155485I-340J212D01*
G03X1077934Y153068I-1682J-1985D01*
G02X1077534Y152602I-394J-66D01*
G03X1080066Y150432I-34J-2602D01*
G02X1080466Y150898I394J66D01*
G03X1082708Y152124I33J2602D01*
G02X1083306Y152218I340J-212D01*
G03X1084349Y151681I1682J1985D01*
G01X1084500Y151642D01*
Y148000D01*
X1077000Y140500D01*
Y122000D01*
X1071000Y116000D01*
Y75500D01*
X1070000Y74500D01*
X1040500D01*
G37*
G36*
G01X1031500Y864000D02*
X1028802Y866698D01*
Y883080D01*
G02X1029542Y883290I400J0D01*
G03X1033196Y882944I1958J1210D01*
G02X1033493Y882941I147J-135D01*
G03X1033566Y882862I1727J1523D01*
G02X1033534Y882275I-287J-279D01*
G03X1036650Y882106I1466J-1775D01*
G02X1036682Y882693I287J279D01*
G03X1036842Y882838I-1464J1777D01*
G02X1037402Y882843I283J-283D01*
G03X1037374Y886130I1598J1657D01*
G02X1036814Y886125I-283J283D01*
G03X1036652Y886267I-1597J-1658D01*
G02X1036620Y886864I249J313D01*
G03X1033742Y886572I-1620J1636D01*
G02X1033759Y886250I-110J-167D01*
G03X1033647Y886153I1450J-1788D01*
G02X1033097Y886158I-272J293D01*
G03X1029542Y885710I-1597J-1658D01*
G02X1028802Y885920I-340J210D01*
G01Y888302D01*
X1029000Y888500D01*
Y891500D01*
X1027218Y893282D01*
Y917218D01*
X1027500Y917500D01*
X1069500D01*
X1090066Y896934D01*
Y895559D01*
X1090918Y894707D01*
Y865418D01*
X1089500Y864000D01*
X1031500D01*
G37*
G36*
G01X1196798Y871674D02*
X1214500Y853972D01*
Y840500D01*
X1210500Y836500D01*
X1176000D01*
X1172500Y840000D01*
Y857500D01*
X1169500Y860500D01*
X1163500D01*
X1160000Y857000D01*
Y849500D01*
X1154500Y844000D01*
X1109303D01*
G03X1105515Y844771I-2143J-840D01*
G01X1105514Y844770D01*
X1105372Y844628D01*
X1102000Y848000D01*
Y910500D01*
X1095500Y917000D01*
Y919500D01*
X1097000Y921000D01*
X1148500D01*
X1193951Y875549D01*
G03X1196340Y872223I2049J-1049D01*
G02X1196798Y871828I58J-395D01*
G01Y871674D01*
G37*
G36*
G01X1127051Y765000D02*
G03X1124950Y765232I-1152J-800D01*
G02X1124397Y765243I-271J294D01*
G01X1121643Y767997D01*
G02X1121768Y768648I282J283D01*
G03X1119927Y770489I-553J1288D01*
G02X1119276Y770364I-368J157D01*
G01X1115000Y774640D01*
Y782213D01*
G02X1115655Y782521I400J0D01*
G03Y784679I895J1079D01*
G02X1115000Y784987I-255J308D01*
G01Y799500D01*
X1116500Y801000D01*
X1119976D01*
G02X1120346Y800450I-1J-400D01*
G03X1122946I1300J-526D01*
G02X1123316Y801000I371J150D01*
G01X1126270D01*
G02X1126642Y800452I0J-400D01*
G03X1129248I1303J-517D01*
G02X1129620Y801000I372J148D01*
G01X1132551D01*
G02X1132926Y800463I-1J-400D01*
G03X1134928Y801208I1318J-479D01*
G02X1134840Y801840I195J349D01*
G01X1137480Y804480D01*
X1166500D01*
X1175500Y795480D01*
Y769000D01*
X1171500Y765000D01*
X1147761D01*
G02X1147415Y765600I0J400D01*
G03X1144985I-1215J700D01*
G02X1144639Y765000I-346J-200D01*
G01X1127051D01*
G37*
G36*
G01X1127500Y287000D02*
X1125500Y289000D01*
Y310500D01*
X1142632Y327632D01*
G02X1142974Y327491I142J-141D01*
G01Y327158D01*
X1142911Y327099D01*
G03X1145876Y327156I1514J-1599D01*
G01Y330773D01*
X1155906Y340802D01*
Y340902D01*
X1160882Y345878D01*
Y345882D01*
X1161500Y346500D01*
Y357500D01*
X1162240Y358240D01*
X1162283Y358255D01*
G03X1162171Y362641I-753J2175D01*
G02X1161954Y363252I112J384D01*
G03X1161500Y366352I-1896J1306D01*
G01Y395300D01*
G02X1162211Y395552I400J0D01*
G03X1161884Y397906I1789J1448D01*
G01X1161832Y397785D01*
X1161500D01*
Y398500D01*
X1163500Y400500D01*
X1168447D01*
X1172808Y396139D01*
Y387448D01*
X1171098Y385738D01*
Y381262D01*
X1173500Y378860D01*
Y371631D01*
G03X1173446Y368425I1625J-1631D01*
G01X1173500Y368368D01*
Y368077D01*
X1173396Y368020D01*
G03X1173500Y363927I1104J-2020D01*
G01Y358619D01*
G03Y354381I900J-2119D01*
G01Y338553D01*
X1161548Y326601D01*
Y326048D01*
X1159000Y323500D01*
Y320573D01*
G03X1157714Y318771I1000J-2073D01*
G02X1157137Y318460I-397J46D01*
G03X1155304Y318565I-1037J-2055D01*
G02X1154771Y318875I-138J375D01*
G03X1153296Y316340I-2271J-375D01*
G02X1153829Y316030I138J-375D01*
G03X1154387Y314867I2271J374D01*
G02Y314333I-298J-267D01*
G03X1153881Y313406I1714J-1537D01*
G02X1153348Y313140I-386J106D01*
G03X1154719Y310389I-848J-2140D01*
G02X1155252Y310655I386J-106D01*
G03X1155493Y310575I845J2141D01*
G02X1155774Y310087I-106J-386D01*
G03X1156345Y307900I2226J-587D01*
G02X1156340Y307340I-288J-277D01*
G01X1136000Y287000D01*
X1127500D01*
G37*
G36*
G01X1150500Y672000D02*
X1144000Y678500D01*
X1143372D01*
G02X1143056Y679145I0J400D01*
G03X1140680I-1188J919D01*
G02X1140364Y678500I-316J-245D01*
G01X1138500D01*
X1137173Y679827D01*
X1137162Y679888D01*
G03X1136268Y680997I-1477J-275D01*
G01X1136232Y681012D01*
X1134645Y682600D01*
X1134400D01*
X1134000Y683000D01*
Y684453D01*
G02X1134642Y684771I400J0D01*
G03Y687163I909J1196D01*
G02X1134000Y687481I-242J318D01*
G01Y697500D01*
X1138498Y701998D01*
X1139490D01*
X1141492Y704000D01*
X1156500D01*
X1161000Y708500D01*
X1162000D01*
X1162500Y709000D01*
X1167500D01*
X1171500Y713000D01*
X1172687D01*
X1172727Y712982D01*
G03X1172838Y712937I619J1368D01*
G02X1172828Y712557I-67J-188D01*
G03X1172152Y710107I434J-1438D01*
G02X1172100Y709520I-295J-270D01*
G03X1171527Y708125I915J-1191D01*
G02X1171145Y707671I-396J-54D01*
G03X1172688Y706374I55J-1501D01*
G02X1173070Y706828I396J54D01*
G03X1174125Y709341I-55J1501D01*
G02X1174177Y709928I295J270D01*
G03X1174552Y710350I-915J1191D01*
G02X1175237Y710356I344J-204D01*
G03X1175644Y709920I1279J786D01*
G02Y709269I-232J-326D01*
G03X1175703Y706781I871J-1224D01*
G02Y706109I-216J-336D01*
G03X1177758Y704002I812J-1264D01*
G02X1178420Y704003I331J-224D01*
G03X1180472Y706114I1240J847D01*
G02Y706786I216J336D01*
G03X1180504Y709292I-812J1264D01*
G02X1180508Y709956I225J331D01*
G03X1180284Y712580I-832J1251D01*
G02X1180287Y712947I81J183D01*
G03X1180359Y712980I-590J1381D01*
G01X1180401Y713000D01*
X1182155D01*
X1182193Y712983D01*
G03X1183411I609J1373D01*
G01X1183449Y713000D01*
X1188500D01*
X1188750Y712750D01*
X1194170D01*
G02X1194452Y712066I0J-400D01*
G03X1197548I1548J-1566D01*
G02X1197830Y712750I282J284D01*
G01X1218250D01*
X1220000Y711000D01*
Y704500D01*
X1218771Y703271D01*
G02X1218120Y703398I-283J283D01*
G03X1215102Y700380I-2120J-898D01*
G02X1215229Y699729I-156J-368D01*
G01X1214000Y698500D01*
X1205710D01*
X1205696Y698685D01*
G03X1201304I-2196J-165D01*
G01X1201290Y698500D01*
X1191000D01*
X1189000Y700500D01*
X1175500D01*
X1174999Y699999D01*
G02X1174337Y699722I-399J24D01*
G03Y697458I-987J-1132D01*
G02X1175000Y697157I263J-301D01*
G01Y695549D01*
X1174999Y695541D01*
G03Y695289I1497J-126D01*
G01X1175000Y695281D01*
Y693727D01*
G02X1174344Y693420I-400J0D01*
G03X1172540Y691022I-959J-1156D01*
G02X1172542Y690361I-224J-331D01*
G03X1172546Y687878I847J-1240D01*
G02X1172547Y687216I-224J-331D01*
G03X1173556Y684481I845J-1242D01*
G02X1174000Y684083I44J-398D01*
G01Y679000D01*
X1173000Y678000D01*
X1167500D01*
X1164306Y674806D01*
X1164201Y674826D01*
G03X1162691Y674224I-287J-1474D01*
G02X1162030Y674239I-325J232D01*
G03X1159523Y674258I-1260J-818D01*
G02X1158859Y674257I-332J223D01*
G03X1156344Y672614I-1246J-839D01*
G02X1156006Y672000I-338J-214D01*
G01X1150500D01*
G37*
G36*
G01X1143998Y704502D02*
X1143000Y705500D01*
Y708500D01*
X1144000Y709500D01*
X1158500D01*
X1159000Y709000D01*
Y707209D01*
X1156292Y704502D01*
X1143998D01*
G37*
G36*
G01X1203000Y201500D02*
X1202000Y202500D01*
Y213500D01*
X1197500Y218000D01*
X1159500D01*
X1158500Y219000D01*
Y227500D01*
X1160000Y229000D01*
X1188000D01*
X1192800Y224200D01*
X1193601D01*
X1194002Y223798D01*
X1204502D01*
X1206502Y221798D01*
X1213998D01*
X1214199Y222000D01*
X1239874D01*
G03X1239939Y221911I2133J1490D01*
G02X1239806Y221312I-317J-244D01*
G03X1239356Y216983I1194J-2312D01*
G02X1239162Y216277I-252J-310D01*
G03X1241035Y215715I338J-2277D01*
G02X1241262Y216411I267J298D01*
G03X1243254Y217699I-262J2589D01*
G02X1244000Y217499I346J-200D01*
G01Y202500D01*
X1243000Y201500D01*
X1241200D01*
G02X1240948Y202211I0J400D01*
G03X1238052I-1448J1789D01*
G02X1237800Y201500I-252J-311D01*
G01X1211200D01*
G02X1210800Y201915I0J400D01*
G03X1206200I-2300J85D01*
G02X1205800Y201500I-400J-15D01*
G01X1203000D01*
G37*
G36*
G01X1207000Y223000D02*
X1205000Y225000D01*
X1194500D01*
X1193000Y226500D01*
Y230000D01*
X1189000Y234000D01*
X1187640D01*
G03X1185360I-1140J-2000D01*
G01X1172140D01*
G03X1169860I-1140J-2000D01*
G01X1167140D01*
G03X1164860I-1140J-2000D01*
G01X1159000D01*
X1156500Y236500D01*
Y251500D01*
X1160000Y255000D01*
X1178931D01*
G03X1182423I1746J1500D01*
G01X1213500D01*
X1215000Y253500D01*
Y224500D01*
X1213500Y223000D01*
X1207000D01*
G37*
G36*
G01X1201798Y378870D02*
X1209798Y370870D01*
Y259798D01*
X1206500Y256500D01*
X1182986D01*
X1182972Y256684D01*
G03X1178382I-2295J-184D01*
G01X1178368Y256500D01*
X1161000D01*
X1158000Y259500D01*
Y266347D01*
X1158552Y266899D01*
Y284550D01*
X1185952Y311950D01*
Y311952D01*
X1186000Y312000D01*
Y344447D01*
X1189452Y347899D01*
Y347952D01*
X1193500Y352000D01*
Y373000D01*
X1189452Y377048D01*
Y377101D01*
X1187002Y379551D01*
Y415001D01*
X1188000Y416000D01*
X1201798D01*
Y378870D01*
G37*
G36*
G01X1274500Y493615D02*
X1251566Y470682D01*
Y469566D01*
X1250703Y468703D01*
X1249502Y469905D01*
Y471199D01*
G03X1248977Y474728I-1702J1550D01*
G02X1248822Y475246I205J343D01*
G03X1245573Y474272I-2072J1004D01*
G02X1245728Y473754I-205J-343D01*
G03X1246098Y471199I2072J-1004D01*
G01Y468495D01*
X1248297Y466297D01*
X1247500Y465500D01*
Y443203D01*
X1247498Y443202D01*
X1246683D01*
X1244348Y440867D01*
Y437633D01*
X1246683Y435298D01*
X1247498D01*
X1247500Y435297D01*
Y266293D01*
G02X1246953Y265921I-400J0D01*
G03X1247341Y261270I-953J-2421D01*
G01X1247388Y261298D01*
X1248202D01*
X1250500Y259000D01*
Y246000D01*
X1248500Y244000D01*
X1238500D01*
X1228000Y254500D01*
Y370500D01*
X1225952Y372548D01*
Y372601D01*
X1212952Y385601D01*
Y416873D01*
X1212500Y417325D01*
Y430500D01*
X1218500Y436500D01*
Y438360D01*
G03Y440640I-2000J1140D01*
G01Y448500D01*
X1218250Y448750D01*
Y450567D01*
G03Y454433I-1250J1933D01*
G01Y477250D01*
X1245000Y504000D01*
X1271000D01*
X1274500Y500500D01*
Y493615D01*
G37*
G36*
G01X1243393Y162500D02*
X1239060Y166833D01*
Y183507D01*
X1250152Y194599D01*
Y194652D01*
X1258206Y202706D01*
X1258275Y202714D01*
G03X1260286Y204725I-275J2286D01*
G01X1260294Y204794D01*
X1260714Y205214D01*
X1260807Y205206D01*
G03X1263294Y207693I193J2294D01*
G01X1263286Y207786D01*
X1264714Y209214D01*
X1264807Y209206D01*
G03X1267294Y211693I193J2294D01*
G01X1267286Y211786D01*
X1274000Y218500D01*
Y232300D01*
G02X1274711Y232552I400J0D01*
G03Y235448I1789J1448D01*
G02X1274000Y235700I-311J252D01*
G01Y320000D01*
X1293474Y339474D01*
X1303709Y329239D01*
X1303703Y329148D01*
G03X1305852Y331297I2297J-148D01*
G01X1305761Y331291D01*
X1305531Y331522D01*
G02X1305841Y332203I283J282D01*
G03X1307548Y336204I159J2297D01*
G02Y336796I269J296D01*
G03X1304452I-1548J1704D01*
G02Y336204I-269J-296D01*
G03X1303703Y334341I1548J-1704D01*
G02X1303022Y334031I-399J-27D01*
G01X1295526Y341526D01*
X1309000Y355000D01*
X1361500D01*
X1362714Y353785D01*
Y341214D01*
X1322786Y301286D01*
X1322693Y301294D01*
G03X1320206Y298807I-193J-2294D01*
G01X1320214Y298714D01*
X1295500Y274000D01*
Y208000D01*
X1256294Y168794D01*
X1256225Y168786D01*
G03X1254214Y166775I275J-2286D01*
G01X1254206Y166706D01*
X1250000Y162500D01*
X1243393D01*
G37*
G36*
G01X1362500Y252000D02*
X1361500Y253000D01*
Y268000D01*
X1379000Y285500D01*
Y290300D01*
G02X1379711Y290552I400J0D01*
G03Y293448I1789J1448D01*
G02X1379000Y293700I-311J252D01*
G01Y311300D01*
G02X1379415Y311700I400J0D01*
G03Y316300I85J2300D01*
G02X1379000Y316700I-15J400D01*
G01Y354500D01*
X1381500Y357000D01*
Y392000D01*
X1379000Y394500D01*
Y443500D01*
X1364552Y457948D01*
X1364607Y458073D01*
G03X1361573Y461107I-2107J927D01*
G01X1361448Y461052D01*
X1355794Y466706D01*
X1355786Y466775D01*
G03X1353775Y468786I-2286J-275D01*
G01X1353706Y468794D01*
X1352000Y470500D01*
Y488000D01*
X1353000Y489000D01*
X1389500D01*
X1397000Y481500D01*
Y255000D01*
X1394000Y252000D01*
X1362500D01*
G37*
%LPC*%
G75*
G36*
G01X768457Y847705D02*
G03X768520Y847112I296J-268D01*
G02X765243Y846919I-1520J-2112D01*
G03X765236Y847516I-270J295D01*
G02X768457Y847705I1514J1734D01*
G37*
G36*
G01X59410Y813912D02*
G03X58818Y813986I-329J-228D01*
G02X59198Y817028I-1514J1734D01*
G03X59790Y816954I329J228D01*
G02X59410Y813912I1514J-1734D01*
G37*
G36*
G01X60484Y800934D02*
G03X59934Y800712I-175J-359D01*
G02X58780Y803574I-2162J792D01*
G03X59330Y803796I175J359D01*
G02X60484Y800934I2162J-792D01*
G37*
G36*
G01X82723Y763296D02*
G03X82922Y763014I182J-83D01*
G02X82992Y763019I199J-2293D01*
G03X83371Y763431I-21J399D01*
G02X85792Y761205I2301J73D01*
G03X85413Y760793I21J-399D01*
G02X80919Y761419I-2301J-73D01*
G03X80550Y761940I-381J121D01*
G02X82723Y763296I74J2301D01*
G37*
G36*
G01X68089Y758491D02*
G03X67550Y758175I-143J-373D01*
G02X63328Y759736I-2278J328D01*
G03X63240Y760262I-338J214D01*
G02X65859Y764035I1442J1794D01*
G03X66463Y764358I205J344D01*
G02X70540Y762777I2299J-119D01*
G03X70562Y762245I309J-254D01*
G02X68089Y758491I-1652J-1603D01*
G37*
G36*
G01X738833Y756998D02*
G03X738753Y757664I-256J307D01*
G02X738630Y762271I1147J2336D01*
G03X738781Y762822I-195J350D01*
G02X742092Y762101I1987J1162D01*
G03X741999Y761537I230J-328D01*
G02X741567Y758002I-2099J-1537D01*
G03X741647Y757336I256J-307D01*
G02X738833Y756998I-1147J-2336D01*
G37*
G36*
G01X219346Y724601D02*
G03X219150Y725269I-287J278D01*
G02X222169Y725684I969J4140D01*
G03X222160Y724988I193J-351D01*
G02X219346Y724601I-1160J-1988D01*
G37*
G36*
G01X70232Y720785D02*
G03X69684Y720797I-280J-285D01*
G02X69761Y724152I-1537J1714D01*
G03X70309Y724140I280J285D01*
G02X70232Y720785I1537J-1714D01*
G37*
G36*
G01X74347Y386464D02*
X73619D01*
G02Y389488I-1736J1512D01*
G01X74347D01*
G02Y386464I1736J-1512D01*
G37*
G36*
G01X64795Y386309D02*
X64553Y386302D01*
X64496Y386238D01*
G02X64410Y389404I-1713J1538D01*
G01X64471Y389343D01*
X64713Y389350D01*
X64770Y389414D01*
G02X64856Y386248I1713J-1538D01*
G01X64795Y386309D01*
G37*
G36*
G01X45413Y389489D02*
G03X45946Y389490I266J299D01*
G02X45953Y386056I1537J-1714D01*
G03X45420Y386055I-266J-299D01*
G02X45413Y389489I-1537J1714D01*
G37*
G36*
G01X55291Y386213D02*
X55229Y386273D01*
X55000Y386260D01*
X54945Y386194D01*
G02X54774Y389339I-1762J1481D01*
G01X54837Y389279D01*
X55066Y389292D01*
X55122Y389358D01*
G02X55291Y386213I1761J-1482D01*
G37*
G36*
G01X194386Y343719D02*
Y343349D01*
X194449Y343290D01*
G02X191299I-1575J-1679D01*
G01X191362Y343349D01*
Y343719D01*
X191299Y343778D01*
G02X194449I1575J1679D01*
G01X194386Y343719D01*
G37*
G36*
G01Y332569D02*
Y332199D01*
X194449Y332140D01*
G02X191299I-1575J-1679D01*
G01X191362Y332199D01*
Y332569D01*
X191299Y332628D01*
G02X194449I1575J1679D01*
G01X194386Y332569D01*
G37*
G36*
G01X177884Y327238D02*
X177514D01*
X177455Y327174D01*
G02Y330324I-1679J1575D01*
G01X177514Y330260D01*
X177884D01*
X177943Y330324D01*
G02Y327174I1679J-1575D01*
G01X177884Y327238D01*
G37*
G36*
G01X209955Y324935D02*
G03X210517I281J285D01*
G02Y321659I1617J-1638D01*
G03X209955I-281J-285D01*
G02Y324935I-1617J1638D01*
G37*
G36*
G01X201072Y321680D02*
G03X200502I-285J-281D01*
G02Y324914I-1638J1617D01*
G03X201072I285J281D01*
G02Y321680I1638J-1617D01*
G37*
G36*
G01X184352Y319454D02*
G03X184008Y319925I-393J74D01*
G02X186557Y321783I287J2284D01*
G03X186901Y321312I393J-74D01*
G02X188327Y320566I-287J-2284D01*
G03X188872Y320518I298J267D01*
G02X190138Y321006I1424J-1809D01*
G03X190508Y321450I-27J399D01*
G02X192952Y319412I2287J259D01*
G03X192582Y318968I27J-399D01*
G02X188582Y317171I-2287J-259D01*
G03X188037Y317219I-298J-267D01*
G02X184352Y319454I-1423J1809D01*
G37*
G36*
G01X190524Y297784D02*
G03X190968Y297488I387J100D01*
G02X191166Y297507I319J-2280D01*
G03X191543Y297884I-23J400D01*
G02X193970Y295457I2298J-129D01*
G03X193593Y295080I23J-400D01*
G02X189066Y294634I-2298J129D01*
G03X188622Y294930I-387J-100D01*
G02X187760Y294970I-326J2279D01*
G03X187278Y294674I-93J-389D01*
G02X185574Y297448I-2239J535D01*
G03X186056Y297744I93J389D01*
G02X190524Y297784I2239J-535D01*
G37*
G36*
G01X211995Y293398D02*
X211625D01*
X211566Y293334D01*
G02Y296484I-1679J1575D01*
G01X211625Y296420D01*
X211995D01*
X212054Y296484D01*
G02Y293334I1679J-1575D01*
G01X211995Y293398D01*
G37*
G36*
G01X202547D02*
X202177D01*
X202118Y293334D01*
G02Y296484I-1679J1575D01*
G01X202177Y296420D01*
X202547D01*
X202606Y296484D01*
G02Y293334I1679J-1575D01*
G01X202547Y293398D01*
G37*
G36*
G01X177350D02*
X176980D01*
X176921Y293334D01*
G02Y296484I-1679J1575D01*
G01X176980Y296420D01*
X177350D01*
X177409Y296484D01*
G02Y293334I1679J-1575D01*
G01X177350Y293398D01*
G37*
G36*
G01X167901Y292798D02*
X167531D01*
X167472Y292734D01*
G02Y295884I-1679J1575D01*
G01X167531Y295820D01*
X167901D01*
X167960Y295884D01*
G02Y292734I1679J-1575D01*
G01X167901Y292798D01*
G37*
G36*
G01X262038Y205939D02*
G03X261572Y205606I-71J-394D01*
G02X257560Y208167I-2572J394D01*
G03Y208833I-222J333D01*
G02X261572Y211394I1440J2167D01*
G03X262038Y211061I395J61D01*
G02Y205939I462J-2561D01*
G37*
G36*
G01X1007050Y82277D02*
G03X1006450I-300J-264D01*
G02Y85723I-1950J1723D01*
G03X1007050I300J264D01*
G02X1010950I1950J-1723D01*
G03X1011550I300J264D01*
G02X1013802Y86584I1949J-1723D01*
G03X1014241Y87058I46J397D01*
G02X1016409Y85200I2259J442D01*
G03X1016008Y84694I-15J-400D01*
G02X1011550Y82277I-2508J-694D01*
G03X1010950I-300J-264D01*
G02X1007050I-1950J1723D01*
G37*
G36*
G01X310904Y83723D02*
G03X311163Y84279I-104J387D01*
G02X313846Y83027I2087J971D01*
G03X313587Y82471I104J-387D01*
G02X312075Y79271I-2087J-971D01*
G03X311779Y78827I100J-387D01*
G02X308925Y80729I-2279J-327D01*
G03X309221Y81173I-100J387D01*
G02X310904Y83723I2279J326D01*
G37*
G36*
G01X1019050Y73777D02*
G03X1018450I-300J-264D01*
G02Y77223I-1950J1723D01*
G03X1019050I300J264D01*
G02Y73777I1950J-1723D01*
G37*
G36*
G01X1072448Y40156D02*
X1069284D01*
G02Y46378I-2355J3111D01*
G01X1072448D01*
G02Y40156I2355J-3111D01*
G37*
G36*
G01X331940Y36333D02*
G03Y35667I222J-333D01*
G02X329060I-1440J-2167D01*
G03Y36333I-222J333D01*
G02X331940I1440J2167D01*
G37*
G36*
G01X79185Y833568D02*
G02X77093Y834266I-1686J-1568D01*
G03X77315Y834932I-71J394D01*
G02X79407Y834234I1686J1568D01*
G03X79185Y833568I71J-394D01*
G37*
G36*
G01X90413Y736261D02*
G02X90403Y733835I1952J-1221D01*
G03X89724Y733838I-340J-209D01*
G02X85920Y733691I-1952J1221D01*
G03X85340Y733759I-322J-237D01*
G02X82521Y733633I-1491J1754D01*
G03X81991Y733572I-231J-327D01*
G02X78220Y734061I-1719J1531D01*
G03X77503Y734054I-357J-181D01*
G02X77484Y736101I-2071J1004D01*
G03X78201Y736108I357J181D01*
G02X81600Y736983I2071J-1005D01*
G03X82130Y737044I231J327D01*
G02X85701Y736881I1719J-1531D01*
G03X86281Y736813I322J237D01*
G02X89734Y736264I1491J-1754D01*
G03X90413Y736261I340J209D01*
G37*
G36*
G01X1130884Y227957D02*
G02Y230043I-2384J1043D01*
G03X1131616I366J161D01*
G02Y227957I2384J-1043D01*
G03X1130884I-366J-161D01*
G37*
G36*
G01X1024884Y50457D02*
G02Y52543I-2384J1043D01*
G03X1025616I366J161D01*
G02Y50457I2384J-1043D01*
G03X1024884I-366J-161D01*
G37*
G36*
G01X317950Y9277D02*
G02Y12723I-1950J1723D01*
G03X318550I300J264D01*
G02X321106Y13530I1949J-1723D01*
G03X321572Y14063I93J389D01*
G02X322277Y16950I2428J937D01*
G03Y17550I-264J300D01*
G02Y21450I1723J1950D01*
G03Y22050I-264J300D01*
G02X325723I1723J1950D01*
G03Y21450I264J-300D01*
G02Y17550I-1723J-1950D01*
G03Y16950I264J-300D01*
G02X323394Y12470I-1723J-1950D01*
G03X322928Y11937I-93J-389D01*
G02X318550Y9277I-2428J-937D01*
G03X317950I-300J-264D01*
G37*
G36*
G01X54125Y941335D02*
G03Y940680I230J-328D01*
G02X51483I-1321J-1885D01*
G03Y941335I-230J328D01*
G02X54125I1321J1885D01*
G37*
G36*
G01X53140Y928313D02*
G03X52400I-370J-152D01*
G02X50201Y931487I-2130J873D01*
G03X50571Y932005I-12J400D01*
G02X54900Y933559I2199J681D01*
G03X55640I370J152D01*
G02X59900I2130J-873D01*
G03X60640I370J152D01*
G02X62839Y930385I2130J-873D01*
G03X62469Y929867I12J-400D01*
G02X58140Y928313I-2199J-681D01*
G03X57400I-370J-152D01*
G02X53140I-2130J873D01*
G37*
G36*
G01X353530Y126949D02*
G03X353030Y126549I-100J-388D01*
G02X351828Y128051I-1601J-49D01*
G03X352328Y128451I100J388D01*
G02X353530Y126949I1601J49D01*
G37*
G36*
G01X336112Y130000D02*
X336122Y129969D01*
G02X333078I-1522J-501D01*
G01X333088Y130000D01*
Y132499D01*
X333078Y132530D01*
G02X335339Y134453I1522J501D01*
G03X335918Y134743I184J355D01*
G02X336757Y133142I1482J-244D01*
G03X336189Y132831I-171J-361D01*
G02X336122Y132530I-1590J196D01*
G01X336112Y132499D01*
Y130000D01*
G37*
G36*
G01X328163Y127144D02*
G02X327777Y129072I-2234J555D01*
G03X328464Y129149I321J239D01*
G02X328826Y127338I1465J-649D01*
G03X328163Y127144I-275J-290D01*
G37*
G36*
G01X344296Y100452D02*
G03X343704I-296J-269D01*
G02Y103548I-1704J1548D01*
G03X344296I296J269D01*
G02Y100452I1704J-1548D01*
G37*
G36*
G01X359048Y77796D02*
G03Y77204I269J-296D01*
G02X355952I-1548J-1704D01*
G03Y77796I-269J296D01*
G02X359048I1548J1704D01*
G37*
G36*
G01X384050Y51277D02*
G03X383450I-300J-264D01*
G02X380060Y55167I-1950J1723D01*
G03Y55833I-222J333D01*
G02X382940I1440J2167D01*
G03Y55167I222J-333D01*
G02X383450Y54723I-1439J-2168D01*
G03X384050I300J264D01*
G02Y51277I1950J-1723D01*
G37*
G36*
G01X405693Y949744D02*
G03X405497Y949501I-1J-200D01*
G02X400963Y949259I-2247J-501D01*
G03X400593Y949703I-397J45D01*
G02X398463Y952259I157J2297D01*
G03X398093Y952703I-397J45D01*
G02X400537Y954741I157J2297D01*
G03X400907Y954297I397J-45D01*
G02X402852Y952939I-157J-2297D01*
G03X403585Y952946I365J163D01*
G02X408002Y952175I2119J-900D01*
G03X408379Y951798I400J23D01*
G02X405948Y949541I-129J-2298D01*
G03X405745Y949744I-200J3D01*
G02X405693I-26J2302D01*
G37*
G36*
G01X361296Y929952D02*
G03X360704I-296J-269D01*
G02Y933048I-1704J1548D01*
G03X361296I296J269D01*
G02Y929952I1704J-1548D01*
G37*
G36*
G01X367754Y914449D02*
G03X367185Y914432I-276J-289D01*
G02X367087Y917668I-1685J1568D01*
G03X367656Y917685I276J289D01*
G02X367754Y914449I1685J-1568D01*
G37*
G36*
G01X364414Y905679D02*
G03X364195Y905193I162J-366D01*
G02X361066Y906604I-2195J-693D01*
G03X361285Y907090I-162J366D01*
G02X364414Y905679I2195J693D01*
G37*
G36*
G01X376775Y904083D02*
G03Y903417I221J-333D01*
G02X374225I-1275J-1917D01*
G03Y904083I-221J333D01*
G02X376775I1275J1917D01*
G37*
G36*
G01X394878Y897382D02*
G03X394838Y897952I-299J265D01*
G02X395008Y901590I1492J1753D01*
G03X395034Y902226I-229J328D01*
G02X398797Y904157I1466J1774D01*
G03X399241Y903787I399J27D01*
G02X398987Y899256I259J-2287D01*
G03X398518Y898990I-89J-390D01*
G02X398052Y898178I-2188J716D01*
G03X398092Y897608I299J-265D01*
G02X398532Y894604I-1492J-1753D01*
G03X398680Y894033I336J-218D01*
G02X398744Y890002I-1080J-2033D01*
G03X398581Y889484I199J-347D01*
G02X395356Y890498I-2081J-984D01*
G03X395519Y891016I-199J347D01*
G02X395668Y893251I2081J984D01*
G03X395520Y893822I-336J218D01*
G02X394878Y897382I1080J2033D01*
G37*
G36*
G01X373230Y924343D02*
G02X369932Y923567I-1292J-1905D01*
G03X369808Y924095I-348J197D01*
G02X369511Y927665I1292J1905D01*
G03X369496Y928257I-276J289D01*
G02X368771Y929425I1504J1743D01*
G03X368327Y929721I-387J-100D01*
G02X367593Y934266I-327J2279D01*
G03X367815Y934932I-71J394D01*
G02X369907Y934234I1686J1568D01*
G03X369685Y933568I71J-394D01*
G02X370229Y932575I-1685J-1568D01*
G03X370673Y932279I387J100D01*
G02X372589Y928335I327J-2279D01*
G03X372604Y927743I276J-289D01*
G02X373106Y924871I-1504J-1743D01*
G03X373230Y924343I348J-197D01*
G37*
G36*
G01X584774Y474302D02*
X594674Y484202D01*
X645500D01*
G02Y477798I0J-3202D01*
G01X597326D01*
X587426Y467898D01*
X388885D01*
G02Y474302I0J3202D01*
G01X584774D01*
G37*
G36*
G01X628359Y468180D02*
G03Y467620I286J-280D01*
G02X624641I-1859J-1820D01*
G03Y468180I-286J280D01*
G02X628359I1859J1820D01*
G37*
G36*
G01X621859D02*
G03Y467620I286J-280D01*
G02X618141I-1859J-1820D01*
G03Y468180I-286J280D01*
G02X621859I1859J1820D01*
G37*
G36*
G01X671705Y471983D02*
G02X667175Y472766I-2243J516D01*
G03X666819Y473210I-397J46D01*
G02X669343Y475234I237J2290D01*
G03X669699Y474790I397J-46D01*
G02X670242Y474666I-237J-2290D01*
G03X670767Y474953I135J376D01*
G02X675311Y474511I2243J-517D01*
G03X675975Y474225I400J14D01*
G02X675199Y472425I1525J-1725D01*
G03X674535Y472711I-400J-14D01*
G02X672230Y472270I-1525J1725D01*
G03X671705Y471983I-135J-376D01*
G37*
G36*
G01X610384Y464757D02*
G02X605597Y464801I-2384J1043D01*
G03X604865Y464814I-369J-154D01*
G02X600641Y467720I-2365J1086D01*
G03Y468280I-286J280D01*
G02X604846Y471226I1859J1820D01*
G03X605579Y471253I361J173D01*
G02X610440Y471204I2421J-953D01*
G03X611173Y471164I375J139D01*
G02X615359Y468180I2327J-1163D01*
G03Y467620I286J-280D01*
G02X611116Y464757I-1859J-1820D01*
G03X610384I-366J-161D01*
G37*
G36*
G01X797214Y165644D02*
G03X797140Y165024I211J-340D01*
G02X794286Y165364I-1640J-1616D01*
G03X794360Y165984I-211J340D01*
G02X797214Y165644I1640J1616D01*
G37*
G36*
G01X685455Y130816D02*
G03X684992Y130363I-67J-394D01*
G02X682861Y132544I-2574J-383D01*
G03X683324Y132997I67J394D01*
G02X685455Y130816I2574J383D01*
G37*
G36*
G01X580380Y437641D02*
G03X579820I-280J-286D01*
G02Y441359I-1820J1859D01*
G03X580380I280J286D01*
G02X584064Y441316I1821J-1859D01*
G03X584636I286J279D01*
G02Y437684I1864J-1816D01*
G03X584064I-286J-279D01*
G02X580380Y437641I-1863J1816D01*
G37*
G36*
G01X580880Y429641D02*
G03X580320I-280J-286D01*
G02Y433359I-1820J1859D01*
G03X580880I280J286D01*
G02X584564Y433316I1821J-1859D01*
G03X585136I286J279D01*
G02Y429684I1864J-1816D01*
G03X584564I-286J-279D01*
G02X580880Y429641I-1863J1816D01*
G37*
G36*
G01X648874Y427878D02*
G03X648929Y427304I304J-261D01*
G02X645751Y426997I-1430J-1804D01*
G03X645696Y427571I-304J261D01*
G02X648874Y427878I1430J1804D01*
G37*
G36*
G01X584330Y421641D02*
G03X583770I-280J-286D01*
G02Y425359I-1820J1859D01*
G03X584330I280J286D01*
G02X588035Y425293I1820J-1859D01*
G03X588615I290J276D01*
G02Y421707I1885J-1793D01*
G03X588035I-290J-276D01*
G02X584330Y421641I-1885J1793D01*
G37*
G36*
G01X612380Y420141D02*
G03X611820I-280J-286D01*
G02Y423859I-1820J1859D01*
G03X612380I280J286D01*
G02Y420141I1820J-1859D01*
G37*
G36*
G01X504655Y421408D02*
G03X505235Y421279I348J197D01*
G02X504733Y419251I928J-1306D01*
G03X504160Y419407I-357J-181D01*
G02X504655Y421408I-813J1263D01*
G37*
G36*
G01X612380Y413641D02*
G03X611820I-280J-286D01*
G02Y417359I-1820J1859D01*
G03X612380I280J286D01*
G02Y413641I1820J-1859D01*
G37*
G36*
G01X584330Y407641D02*
G03X583770I-280J-286D01*
G02Y411359I-1820J1859D01*
G03X584330I280J286D01*
G02X588035Y411293I1820J-1859D01*
G03X588615I290J276D01*
G02Y407707I1885J-1793D01*
G03X588035I-290J-276D01*
G02X584330Y407641I-1885J1793D01*
G37*
G36*
G01X649333Y407060D02*
G03X648667I-333J-222D01*
G02Y409940I-2167J1440D01*
G03X649333I333J222D01*
G02Y407060I2167J-1440D01*
G37*
G36*
G01X584330Y394141D02*
G03X583770I-280J-286D01*
G02Y397859I-1820J1859D01*
G03X584330I280J286D01*
G02X588035Y397793I1820J-1859D01*
G03X588615I290J276D01*
G02Y394207I1885J-1793D01*
G03X588035I-290J-276D01*
G02X584330Y394141I-1885J1793D01*
G37*
G36*
G01X709550Y383277D02*
G03X708950I-300J-264D01*
G02Y386723I-1950J1723D01*
G03X709550I300J264D01*
G02Y383277I1950J-1723D01*
G37*
G36*
G01X584380Y376641D02*
G03X583820I-280J-286D01*
G02X580256Y380431I-1820J1859D01*
G03X580249Y381031I-268J297D01*
G02X583770Y384859I1701J1969D01*
G03X584330I280J286D01*
G02X588035Y384793I1820J-1859D01*
G03X588615I290J276D01*
G02Y381207I1885J-1793D01*
G03X588035I-290J-276D01*
G02X587894Y381069I-1889J1789D01*
G03X587901Y380469I268J-297D01*
G02X584380Y376641I-1701J-1969D01*
G37*
G36*
G01X709550Y376277D02*
G03X708950I-300J-264D01*
G02Y379723I-1950J1723D01*
G03X709550I300J264D01*
G02Y376277I1950J-1723D01*
G37*
G36*
G01X611820Y426641D02*
G02X608957Y430884I-1820J1859D01*
G03Y431616I-161J366D01*
G02X609001Y436403I1043J2384D01*
G03X609014Y437135I-154J369D01*
G02X611920Y441359I1086J2365D01*
G03X612480I280J286D01*
G02X615426Y437154I1820J-1859D01*
G03X615453Y436421I173J-361D01*
G02X615404Y431560I-953J-2421D01*
G03X615364Y430827I139J-375D01*
G02X612380Y426641I-1163J-2327D01*
G03X611820I-280J-286D01*
G37*
G36*
G01X836277Y261038D02*
G03X835611Y260964I-309J-254D01*
G02X835333Y263462I-2056J1036D01*
G03X835999Y263536I309J254D01*
G02X840111I2056J-1036D01*
G03X840777Y263462I357J180D01*
G02X844333I1778J-1462D01*
G03X844999Y263536I309J254D01*
G02X848972Y263775I2056J-1036D01*
G03X849638I333J221D01*
G02X853472I1917J-1275D01*
G03X854138I333J221D01*
G02X857972I1917J-1275D01*
G03X858638I333J221D01*
G02X862472I1917J-1275D01*
G03X863138I333J221D01*
G02Y261225I1917J-1275D01*
G03X862472I-333J-221D01*
G02X858638I-1917J1275D01*
G03X857972I-333J-221D01*
G02X854138I-1917J1275D01*
G03X853472I-333J-221D01*
G02X849638I-1917J1275D01*
G03X848972I-333J-221D01*
G02X845277Y261038I-1917J1275D01*
G03X844611Y260964I-309J-254D01*
G02X840499I-2056J1036D01*
G03X839833Y261038I-357J-180D01*
G02X836277I-1778J1462D01*
G37*
G36*
G01X708351Y256952D02*
G03X707759I-296J-269D01*
G02Y260048I-1704J1548D01*
G03X708351I296J269D01*
G02X711759I1704J-1548D01*
G03X712351I296J269D01*
G02Y256952I1704J-1548D01*
G03X711759I-296J-269D01*
G02X708351I-1704J1548D01*
G37*
G36*
G01X680185Y257627D02*
G02Y259373I-2130J873D01*
G03X680925I370J152D01*
G02X684759Y260048I2130J-873D01*
G03X685351I296J269D01*
G02Y256952I1704J-1548D01*
G03X684759I-296J-269D01*
G02X680925Y257627I-1704J1548D01*
G03X680185I-370J-152D01*
G37*
G36*
G01X789796Y781952D02*
G03X789204I-296J-269D01*
G02Y785048I-1704J1548D01*
G03X789796I296J269D01*
G02Y781952I1704J-1548D01*
G37*
G36*
G01X1037698Y201602D02*
G03X1037695Y201058I292J-274D01*
G02X1034321Y201075I-1695J-1558D01*
G03X1034324Y201619I-292J274D01*
G02X1037698Y201602I1695J1558D01*
G37*
G36*
G01X723264Y115080D02*
G03Y114488I269J-296D01*
G02X720168I-1548J-1704D01*
G03Y115080I-269J296D01*
G02X720441Y118701I1548J1704D01*
G03Y119367I-221J333D01*
G02X720012Y119736I1275J1917D01*
G03X719420I-296J-269D01*
G02X716012I-1704J1548D01*
G03X715420I-296J-269D01*
G02Y122832I-1704J1548D01*
G03X716012I296J269D01*
G02X719420I1704J-1548D01*
G03X720012I296J269D01*
G02X720168Y122988I1704J-1548D01*
G03Y123580I-269J296D01*
G02Y126988I1548J1704D01*
G03Y127580I-269J296D01*
G02X723264I1548J1704D01*
G03Y126988I269J-296D01*
G02Y123580I-1548J-1704D01*
G03Y122988I269J-296D01*
G02X723420Y122832I-1548J-1704D01*
G03X724012I296J269D01*
G02X727420I1704J-1548D01*
G03X728012I296J269D01*
G02Y119736I1704J-1548D01*
G03X727420I-296J-269D01*
G02X724012I-1704J1548D01*
G03X723420I-296J-269D01*
G02X722991Y119367I-1704J1548D01*
G03Y118701I221J-333D01*
G02X723264Y115080I-1275J-1917D01*
G37*
G36*
G01X676045Y101604D02*
G03X676061Y101043I293J-272D01*
G02X672782Y100946I-1592J-1663D01*
G03X672766Y101507I-293J272D01*
G02X676045Y101604I1592J1663D01*
G37*
G36*
G01X1055969Y216477D02*
G02X1054031I-969J-1977D01*
G03X1054025Y217199I-176J360D01*
G02X1055975I975J2085D01*
G03X1055969Y216477I170J-362D01*
G37*
G36*
G01X1355800Y672024D02*
G03X1355733Y671291I123J-381D01*
G02X1351898Y669034I-1233J-2291D01*
G03X1351432Y669434I-400J6D01*
G02X1349560Y674167I-432J2566D01*
G03Y674833I-222J333D01*
G02X1353587Y677282I1440J2167D01*
G03X1354120Y676949I397J43D01*
G02X1355800Y672024I880J-2449D01*
G37*
G36*
G01X1357432Y629258D02*
G03X1357766Y628591I297J-268D01*
G02X1355468Y625400I234J-2591D01*
G03X1354848Y625634I-389J-93D01*
G02X1352775Y629691I-1331J1878D01*
G03X1353026Y630194I-129J379D01*
G02X1355007Y633555I2474J806D01*
G03X1355273Y634154I-76J393D01*
G02X1359949Y634620I2227J1346D01*
G03X1360282Y634087I376J-136D01*
G02X1358238Y629585I-282J-2587D01*
G03X1357639Y629518I-270J-295D01*
G02X1357432Y629258I-2135J1487D01*
G37*
G36*
G01X1359595Y617525D02*
G03X1360025Y617095I399J-31D01*
G02X1357905Y614975I175J-2295D01*
G03X1357475Y615405I-399J31D01*
G02X1359595Y617525I-175J2295D01*
G37*
G36*
G01X1379639Y609381D02*
G03Y608848I298J-266D01*
G02X1376353I-1643J-1466D01*
G03Y609381I-298J267D01*
G02X1379639I1643J1466D01*
G37*
G36*
G01X1382336Y600343D02*
Y600007D01*
X1382402Y599948D01*
G02X1379448I-1477J-1633D01*
G01X1379514Y600007D01*
Y600343D01*
X1379448Y600402D01*
G02X1382402I1477J1633D01*
G01X1382336Y600343D01*
G37*
G36*
G01X1383443Y579784D02*
X1383107D01*
X1383048Y579718D01*
G02Y582672I-1633J1477D01*
G01X1383107Y582606D01*
X1383443D01*
X1383502Y582672D01*
G02Y579718I1633J-1477D01*
G01X1383443Y579784D01*
G37*
G36*
G01X1332427Y56398D02*
X1328512D01*
X1312912Y40798D01*
X1306912D01*
X1303912Y37798D01*
X1264912D01*
X1259033Y31919D01*
X1259019Y31894D01*
G02X1255894Y35019I-2019J1106D01*
G01X1255919Y35033D01*
X1263088Y42202D01*
X1302088D01*
X1303967Y44081D01*
X1303981Y44106D01*
G02X1306646Y45210I2019J-1106D01*
G01X1306673Y45202D01*
X1311088D01*
X1326688Y60802D01*
X1332427D01*
X1332454Y60810D01*
G02Y56390I646J-2210D01*
G01X1332427Y56398D01*
G37*
G36*
G01X1341791Y53190D02*
G02X1340227Y51366I709J-2190D01*
G03X1339709Y51810I-395J64D01*
G02X1341273Y53634I-709J2190D01*
G03X1341791Y53190I395J-64D01*
G37*
G36*
G01X1062377Y175781D02*
G03X1062435Y175249I325J-234D01*
G02X1059032Y174879I-1535J-1715D01*
G03X1058974Y175411I-325J234D01*
G02X1062377Y175781I1535J1715D01*
G37*
G36*
G01X1039733Y135915D02*
G03X1039082Y135855I-304J-259D01*
G02X1038837Y138494I-1997J1145D01*
G03X1039488Y138554I304J259D01*
G02X1042699Y139365I1997J-1145D01*
G03X1043224Y139457I211J340D01*
G02X1043817Y136075I1807J-1426D01*
G03X1043292Y135983I-211J-340D01*
G02X1039733Y135915I-1807J1426D01*
G37*
G36*
G01X1059057Y152545D02*
G02X1056916Y152531I-1057J-2045D01*
G03X1056911Y153239I-189J353D01*
G02X1055671Y155434I1057J2045D01*
G03X1055009Y155762I-399J26D01*
G02X1054775Y155583I-1513J1735D01*
G03Y154917I221J-333D01*
G02X1052225I-1275J-1917D01*
G03Y155583I-221J333D01*
G02X1051204Y157332I1275J1917D01*
G03X1050533Y157596I-399J-29D01*
G02X1050516Y157580I-1586J1668D01*
G03Y156988I269J-296D01*
G02X1050243Y153367I-1548J-1704D01*
G03Y152701I221J-333D01*
G02X1047693I-1275J-1917D01*
G03Y153367I-221J333D01*
G02X1047420Y156988I1275J1917D01*
G03Y157580I-269J296D01*
G02X1051264Y159452I1548J1704D01*
G03X1051935Y159188I399J29D01*
G02X1055032Y159218I1565J-1688D01*
G03X1055698Y159514I266J299D01*
G02X1059426Y157693I2302J-14D01*
G03X1059422Y157069I248J-314D01*
G02X1059052Y153253I-1454J-1785D01*
G03X1059057Y152545I189J-353D01*
G37*
G36*
G01X1052504Y886376D02*
G03Y885724I231J-326D01*
G02X1049496I-1504J-2124D01*
G03Y886376I-231J326D01*
G02X1052504I1504J2124D01*
G37*
G36*
G01X1139477Y784359D02*
G03X1138690Y783499I1173J-1863D01*
G02X1138011Y783445I-356J182D01*
G03X1135346Y784156I-1775J-1303D01*
G02X1134787Y784568I-162J366D01*
G03X1134576Y785794I-2187J255D01*
G02X1134813Y786352I359J177D01*
G03X1135877Y787090I-668J2098D01*
G02X1136553Y787013I314J-247D01*
G03X1139028Y785804I1992J939D01*
G02X1139513Y785367I87J-391D01*
G03X1139564Y784577I2187J-255D01*
G02X1139477Y784359I-194J-49D01*
G37*
G36*
G01X1170062Y779306D02*
G03X1169337Y778677I1046J-1938D01*
G02X1168756Y778611I-321J238D01*
G03X1167608Y779120I-1430J-1675D01*
G02X1167326Y779738I51J397D01*
G03X1165956Y783110I-1834J1219D01*
G02X1165799Y783322I42J195D01*
G03X1165806Y783575I-2194J187D01*
G02X1166123Y783743I200J6D01*
G03X1168165Y783462I1286J1787D01*
G02X1168674Y782937I138J-376D01*
G03X1170002Y780036I2044J-819D01*
G02X1170062Y779306I-130J-378D01*
G37*
G36*
G01X1153474Y787701D02*
G03X1152889Y787490I-207J-342D01*
G02X1152291Y789150I-1324J461D01*
G03X1152876Y789361I207J342D01*
G02X1153474Y787701I1324J-461D01*
G37*
G36*
G01X1171716Y783764D02*
G03X1171673Y783144I230J-327D01*
G02X1169913Y783266I-955J-1026D01*
G03X1169956Y783886I-230J327D01*
G02X1171716Y783764I955J1026D01*
G37*
G36*
G01X1154289Y782912D02*
G03X1154215Y782290I210J-340D01*
G02X1152432Y782463I-996J-987D01*
G03X1152479Y783088I-224J331D01*
G02X1154289Y782912I1021J1102D01*
G37*
G36*
G01X1164432Y780039D02*
G03X1163811Y780019I-302J-262D01*
G02X1162214Y782182I-1118J846D01*
G03X1162416Y782770I-137J376D01*
G02X1164872Y782912I1189J743D01*
G03X1165290Y782344I361J-172D01*
G02X1164432Y780039I202J-1387D01*
G37*
G36*
G01X1168073Y769108D02*
G03X1168003Y768490I215J-337D01*
G02X1166249Y768690I-1000J-982D01*
G03X1166319Y769308I-215J337D01*
G02X1168073Y769108I1000J982D01*
G37*
G36*
G01X1152811Y791971D02*
G02X1152798Y793372I-1221J689D01*
G03X1153491Y793379I344J203D01*
G02X1153992Y793893I1221J-689D01*
G03X1153990Y794581I-205J343D01*
G02X1155920Y796480I710J1209D01*
G03X1156623Y796492I348J197D01*
G02X1156646Y795154I1243J-648D01*
G03X1155943Y795142I-348J-197D01*
G02X1155420Y794587I-1243J648D01*
G03X1155422Y793899I205J-343D01*
G02X1153504Y791978I-710J-1209D01*
G03X1152811Y791971I-344J-203D01*
G37*
G36*
G01X1167963Y793881D02*
G02X1166633Y793903I-685J-1223D01*
G03X1166644Y794607I-184J355D01*
G02X1167974Y794585I685J1223D01*
G03X1167963Y793881I184J-355D01*
G37*
G36*
G01X1131452Y793305D02*
G02X1131437Y791996I1232J-669D01*
G03X1130729Y792004I-356J-182D01*
G02X1128284Y791970I-1232J669D01*
G03X1127588Y791963I-346J-200D01*
G02X1125146Y791938I-1228J677D01*
G03X1124457Y791943I-346J-200D01*
G02X1124468Y793365I-1203J720D01*
G03X1125157Y793360I346J200D01*
G02X1127573Y793343I1203J-720D01*
G03X1128269Y793350I346J200D01*
G02X1130744Y793313I1228J-677D01*
G03X1131452Y793305I356J182D01*
G37*
G36*
G01X1142779Y790732D02*
G02X1141412Y790742I-692J-1219D01*
G03X1141417Y791441I-192J351D01*
G02X1140874Y791999I694J1218D01*
G03X1140168Y791998I-353J-189D01*
G02X1138281Y793900I-1237J660D01*
G03X1138290Y794604I-186J354D01*
G02X1139620Y794588I680J1226D01*
G03X1139611Y793884I186J-354D01*
G02X1140167Y793319I-680J-1226D01*
G03X1140873Y793320I353J189D01*
G02X1143337Y793338I1237J-660D01*
G03X1144039Y793340I350J193D01*
G02X1144043Y791992I1231J-670D01*
G03X1143341Y791990I-350J-193D01*
G02X1142784Y791431I-1231J670D01*
G03X1142779Y790732I192J-351D01*
G37*
G36*
G01X1125586Y787709D02*
G02X1125313Y789418I-1226J680D01*
G03X1125934Y789518I271J294D01*
G02X1126207Y787809I1226J-680D01*
G03X1125586Y787709I-271J-294D01*
G37*
G36*
G01X1161866Y786812D02*
G02X1160585Y787025I-844J-1119D01*
G03X1160701Y787725I-125J380D01*
G02X1161982Y787512I844J1119D01*
G03X1161866Y786812I125J-380D01*
G37*
G36*
G01X1166971Y786862D02*
G02X1166022Y785731I439J-1332D01*
G03X1165502Y786168I-396J57D01*
G02X1166451Y787299I-439J1332D01*
G03X1166971Y786862I396J-57D01*
G37*
G36*
G01X1143574Y780883D02*
G02X1140965Y780597I-1251J-633D01*
G03X1140593Y781095I-388J98D01*
G02X1140248Y783839I57J1401D01*
G03X1140481Y784420I-115J383D01*
G02X1143045Y784719I1219J693D01*
G03X1143438Y784207I384J-112D01*
G02X1143829Y781450I32J-1402D01*
G03X1143574Y780883I102J-387D01*
G37*
G36*
G01X1152244Y774989D02*
G02X1150919Y774978I-652J-1241D01*
G03X1150912Y775683I-193J351D01*
G02X1152237Y775694I652J1241D01*
G03X1152244Y774989I193J-351D01*
G37*
G36*
G01X1155278Y681028D02*
G02X1153340Y681183I-1060J-1064D01*
G03X1153389Y681790I-234J324D01*
G02X1153206Y682011I1060J1064D01*
G03X1152543I-331J-224D01*
G02X1150056Y682012I-1243J843D01*
G03X1149394I-331J-224D01*
G02X1147308Y684098I-1244J842D01*
G03Y684760I-224J331D01*
G02X1147307Y687247I842J1244D01*
G03Y687910I-224J331D01*
G02X1147308Y690397I843J1243D01*
G03Y691059I-224J331D01*
G02X1147307Y693546I842J1244D01*
G03Y694209I-224J331D01*
G02X1147308Y696696I843J1243D01*
G03Y697358I-224J331D01*
G02X1149394Y699444I842J1244D01*
G03X1150056I331J224D01*
G02X1152543Y699445I1244J-842D01*
G03X1153206I332J224D01*
G02X1155693Y699444I1243J-843D01*
G03X1156355I331J224D01*
G02X1158842Y699445I1244J-842D01*
G03X1159505I332J224D01*
G02X1161992Y699444I1243J-843D01*
G03X1162654I331J224D01*
G02X1164740Y697358I1244J-842D01*
G03Y696696I224J-331D01*
G02X1164741Y694209I-842J-1244D01*
G03Y693546I224J-332D01*
G02X1164740Y691059I-843J-1243D01*
G03Y690397I224J-331D01*
G02X1164741Y687910I-842J-1244D01*
G03Y687247I224J-332D01*
G02X1162654Y685162I-843J-1243D01*
G03X1161992I-331J-224D01*
G02X1161590Y684760I-1244J842D01*
G03Y684098I224J-331D01*
G02X1159906I-842J-1244D01*
G03Y684760I-224J331D01*
G02X1159505Y685161I842J1243D01*
G03X1158842I-331J-224D01*
G02X1156355Y685162I-1243J843D01*
G03X1155693I-331J-224D01*
G02X1155291Y684760I-1244J842D01*
G03Y684098I224J-331D01*
G02X1155327Y681635I-842J-1244D01*
G03X1155278Y681028I234J-324D01*
G37*
G36*
G01X1198147Y342875D02*
G03X1197613I-267J-298D01*
G02Y346301I-1538J1713D01*
G03X1198147I267J298D01*
G02Y342875I1538J-1713D01*
G37*
G36*
G01X1172039Y288614D02*
X1171515D01*
X1171456Y288550D01*
G02Y291700I-1679J1575D01*
G01X1171515Y291636D01*
X1172039D01*
X1172098Y291700D01*
G02Y288550I1679J-1575D01*
G01X1172039Y288614D01*
G37*
G36*
G01X1191005Y288288D02*
X1190615D01*
X1190556Y288225D01*
G02Y291375I-1679J1575D01*
G01X1190615Y291312D01*
X1191005D01*
X1191064Y291375D01*
G02Y288225I1679J-1575D01*
G01X1191005Y288288D01*
G37*
G36*
G01X1324928Y338434D02*
G03X1324625Y337885I66J-395D01*
G02X1321933Y339231I-2125J-885D01*
G03X1322190Y339803I-98J388D01*
G02X1322730Y342907I2310J1197D01*
G03Y343493I-273J293D01*
G02X1326412Y347165I1770J1907D01*
G03X1327012Y347178I294J271D01*
G02X1330950Y347223I1988J-1678D01*
G03X1331550I300J264D01*
G02X1335450I1950J-1723D01*
G03X1336050I300J264D01*
G02X1340151Y346964I1950J-1723D01*
G03X1340688Y346846I331J225D01*
G02X1340014Y343516I1185J-1973D01*
G03X1339720Y343548I-162J-118D01*
G02X1339611Y343457I-1721J1951D01*
G03Y343143I124J-157D01*
G02X1336050Y339377I-1611J-2043D01*
G03X1335450I-300J-264D01*
G02X1331550I-1950J1723D01*
G03X1330950I-300J-264D01*
G02X1327088Y339335I-1950J1723D01*
G03X1326488Y339322I-294J-271D01*
G02X1324928Y338434I-1988J1678D01*
G37*
G36*
G01X1381630Y273627D02*
G02Y275373I-2130J873D01*
G03X1382370I370J152D01*
G02Y273627I2130J-873D01*
G03X1381630I-370J-152D01*
G37*
G54D41*
X425278Y802000D03*
X444778Y802100D03*
X438278D03*
X431778Y802000D03*
X456278Y802100D03*
X475778D03*
X462778D03*
X469278D03*
X330900Y134500D03*
X338000Y127500D03*
X357394Y131496D03*
X362009Y148819D03*
X355040Y180000D03*
X362017Y183492D03*
X374577Y164559D03*
X368320Y183460D03*
X365187Y186605D03*
X390354Y136221D03*
X380906Y136220D03*
X392240Y129000D03*
X383680Y129030D03*
X402950Y133050D03*
X402800Y129180D03*
X456103Y330117D03*
X448227D03*
X452223Y333983D03*
X448227Y334054D03*
X456103D03*
X456055Y338000D03*
X452055D03*
X440353Y349802D03*
X444290D03*
X440353Y369487D03*
X444290Y365550D03*
X440353Y353739D03*
X444290Y357676D03*
Y369487D03*
X436416D03*
X440353Y357676D03*
X444290Y353739D03*
X440353Y365550D03*
X436416Y353739D03*
Y361613D03*
X444290Y385237D03*
Y377363D03*
X440353Y381300D03*
X436416Y377363D03*
X444290Y381300D03*
X440353Y377363D03*
X436416Y381300D03*
X440353Y400985D03*
Y389174D03*
X444290Y400985D03*
X436416D03*
X444290Y389174D03*
X436416D03*
Y404922D03*
Y408859D03*
X444290Y404922D03*
Y408859D03*
X440353D03*
Y404922D03*
X444323Y416883D03*
X436523Y416683D03*
X440353Y412796D03*
X442535Y426770D03*
X460040Y349802D03*
X448227D03*
X455825Y349840D03*
X452165Y349470D03*
X456103Y365550D03*
Y357676D03*
X460040Y369487D03*
Y361613D03*
X448227Y369487D03*
Y361613D03*
Y353739D03*
X456103Y369487D03*
Y353739D03*
Y361613D03*
X460040Y357676D03*
Y365550D03*
X448227D03*
Y357676D03*
X456103Y385237D03*
Y377363D03*
X460040Y381300D03*
X448227D03*
X460040Y385237D03*
X456103Y381300D03*
X460040Y377363D03*
X448227Y385237D03*
Y377363D03*
X460040Y389174D03*
X448227D03*
X456103Y400985D03*
X460040D03*
X456103Y393111D03*
X460040D03*
Y397048D03*
X448227Y400985D03*
Y393111D03*
X456103Y389174D03*
X456223Y404883D03*
Y408783D03*
X456103Y412796D03*
X460023Y408883D03*
X452123Y416783D03*
X460040Y412796D03*
X448227D03*
X452223Y404883D03*
X448227Y408859D03*
X452223Y408783D03*
X448227Y404922D03*
X450725Y425460D03*
X475788Y369487D03*
X467914D03*
Y361613D03*
Y365550D03*
Y357676D03*
Y353739D03*
X463977Y365550D03*
Y357676D03*
Y369487D03*
Y361613D03*
Y385237D03*
X475788Y381300D03*
Y377363D03*
X467914Y385237D03*
Y377363D03*
Y381300D03*
X463977Y377363D03*
Y381300D03*
X475788Y400985D03*
Y397048D03*
Y393111D03*
X471851D03*
Y397048D03*
X475788Y389174D03*
X467914Y400985D03*
Y397048D03*
Y393111D03*
Y389174D03*
X463977Y393111D03*
Y397048D03*
Y400985D03*
X471851D03*
Y389174D03*
X463977D03*
Y408859D03*
Y404922D03*
X467914Y408859D03*
Y404922D03*
X471851Y412796D03*
X475788D03*
X471851Y416733D03*
X467914Y412796D03*
X475788Y424607D03*
X491536Y385237D03*
Y377363D03*
X479725Y381300D03*
X491536D03*
X479725Y385237D03*
Y377363D03*
X491536Y400985D03*
Y393111D03*
X479725Y397048D03*
Y389174D03*
X491536Y397048D03*
Y389174D03*
X479725Y400985D03*
Y393111D03*
X491536Y416733D03*
Y408859D03*
X487599Y416733D03*
X483662Y408859D03*
X487599Y404922D03*
X479725Y412796D03*
X491536D03*
Y404922D03*
X483662Y412796D03*
Y404922D03*
X479725Y416733D03*
X491536Y420670D03*
Y424607D03*
X483662D03*
X487599D03*
Y420670D03*
X503347Y381300D03*
X495473Y385237D03*
Y377363D03*
X503347Y397048D03*
Y389174D03*
X495473Y400985D03*
Y393111D03*
X499410Y416733D03*
Y412796D03*
Y408859D03*
X503347D03*
Y404922D03*
X495473Y416733D03*
Y412796D03*
Y408859D03*
X499410Y420670D03*
Y424607D03*
X495473D03*
Y420670D03*
X1126642Y785505D03*
X1123200Y783900D03*
X1139858Y692074D03*
X1139000Y685667D03*
X1190000Y705500D03*
G54D47*
X345929Y183000D03*
X348429Y130000D03*
X352500Y113000D03*
X436416Y357676D03*
X458685Y425710D03*
X463945Y349700D03*
X466655Y425340D03*
X472055Y425000D03*
X492555Y431250D03*
X507355Y390800D03*
X505922Y415371D03*
G54D40*
X285500Y330000D03*
X286000Y336000D03*
X336000Y27000D03*
X1034500Y51500D03*
X606000Y918500D03*
X630500Y912000D03*
X682500Y917500D03*
X725000Y189000D03*
X731716Y156500D03*
X930500Y219000D03*
X936500D03*
X930500Y232000D03*
X936500D03*
Y225500D03*
X930500D03*
X961000Y212500D03*
X638500Y409000D03*
X670000Y395000D03*
X670500Y414000D03*
X708500Y371000D03*
X670454Y94544D03*
X701949Y118331D03*
X697248Y128000D03*
X703053Y133568D03*
X727248Y141500D03*
X895000Y96000D03*
X899500Y92500D03*
X1065000Y154000D03*
X1058000Y889500D03*
Y902500D03*
Y896000D03*
G54D39*
X153937Y238898D03*
Y246772D03*
Y260551D03*
X224015Y246772D03*
Y260551D03*
G54D52*
X1367067Y42323D03*
Y60039D03*
Y78544D03*
Y96260D03*
X1296000Y319500D03*
Y329500D03*
G54D50*
X1272441Y7087D03*
X1299213D03*
G54D37*
X58804Y699720D03*
X111000Y981500D03*
X396500Y910500D03*
X419500Y914000D03*
X632500Y530000D03*
X471480Y105660D03*
X866112Y85626D03*
X902000Y63000D03*
X937000D03*
X1351900Y524600D03*
X1084500Y223500D03*
X1089500Y405000D03*
G54D43*
X590315Y9134D03*
Y19134D03*
X649527Y9134D03*
Y19134D03*
Y29134D03*
G54D42*
X432678Y827300D03*
X453878Y824900D03*
X482778Y832000D03*
G54D53*
X1119060Y791083D03*
X1129501Y776929D03*
X1134245Y769145D03*
X1127945Y769970D03*
X1120400Y781600D03*
X1130610Y788820D03*
X1134145Y788450D03*
X1132600Y784822D03*
X1120529Y786350D03*
X1138961Y776940D03*
X1145265Y776945D03*
X1138545Y787952D03*
X1145740Y789140D03*
X1136236Y782142D03*
X1149400Y800000D03*
X1167326Y776936D03*
X1157871Y773728D03*
X1158092Y787715D03*
X1171108Y777368D03*
G54D36*
X35304Y832220D03*
X44804Y837220D03*
X55304Y669720D03*
X58804Y710220D03*
X59272Y790504D03*
X55022Y826720D03*
X66022Y827254D03*
X76804Y710220D03*
X77272Y724004D03*
X75432Y758844D03*
X84804Y808720D03*
X84221Y836078D03*
X70909Y847325D03*
X95304Y686220D03*
X94804Y708220D03*
X99804Y709220D03*
X86404Y774720D03*
X85304Y768720D03*
X93347Y765754D03*
X129304Y798720D03*
X145500Y283500D03*
X194500Y724000D03*
X212500Y716500D03*
X204500Y721000D03*
X218000Y801500D03*
X302000Y94300D03*
X328000Y285000D03*
X392500Y718500D03*
X682968Y758284D03*
X719918Y754734D03*
X763500Y839500D03*
X768000Y833000D03*
X1003000Y59500D03*
X34304Y897720D03*
X41304Y927220D03*
X115500Y983500D03*
X329055Y569500D03*
X321780Y575000D03*
X521500Y632500D03*
X862500Y621250D03*
X339500Y936500D03*
X380000Y872000D03*
X377000Y927500D03*
X376000Y960000D03*
X384000Y926500D03*
X383500Y938500D03*
X432000Y933500D03*
X378255Y471840D03*
X635325Y457500D03*
X645500Y459500D03*
X654300Y490300D03*
X732500Y455500D03*
X736000Y464500D03*
X728500Y482500D03*
X433929Y100000D03*
X459429Y106000D03*
X448929Y99500D03*
X728100Y213800D03*
X747000Y210000D03*
X775748Y188500D03*
X832000Y137500D03*
X642800Y433587D03*
X652714Y428214D03*
X687968Y781784D03*
X702918Y782734D03*
X735000Y780500D03*
X700000Y60500D03*
X715716Y82652D03*
X728966Y65466D03*
X762250Y71000D03*
X761000Y88500D03*
Y82500D03*
X872000Y75500D03*
X996500Y167000D03*
X1023000Y155000D03*
X1028000Y164500D03*
X1023600Y173000D03*
X1035922Y209578D03*
X1040000Y182000D03*
X1052500Y187500D03*
X1045968Y185500D03*
X771000Y464000D03*
X826000Y465078D03*
X874450Y463500D03*
X992000Y505500D03*
X1007500Y507000D03*
X1314500Y921500D03*
X1330500Y441000D03*
X1332000Y459250D03*
X1323500Y452500D03*
X1347000Y48000D03*
X1343500Y112000D03*
X1335000Y443250D03*
X1352000Y85500D03*
X1349500Y112000D03*
X1350000Y276500D03*
X1350084Y296500D03*
X1353000Y390000D03*
Y402000D03*
X1351000Y455750D03*
X1356817Y579012D03*
X1364617Y592912D03*
X1367617Y570012D03*
X1390004Y122600D03*
X1025500Y129500D03*
X1033500Y124000D03*
X1069000Y124500D03*
X1066500Y185500D03*
X1072000Y136000D03*
X1074500Y185500D03*
X1080300Y191000D03*
X1072500Y208924D03*
X1032600Y867657D03*
X1032657Y901500D03*
X1085468Y895968D03*
X1177000Y860000D03*
X1196000Y847500D03*
X1211000D03*
X1136450Y294650D03*
X1209000Y212500D03*
X1181427Y251500D03*
X1188000Y248500D03*
X1208000Y231000D03*
X1207500Y239500D03*
X1201922Y248500D03*
X1216000Y390000D03*
X1243000Y431500D03*
X1234500Y439000D03*
X1242000Y459000D03*
X1295500Y291500D03*
X1304050Y296500D03*
X1307500Y320500D03*
X1308000Y311000D03*
X1312750Y314000D03*
X1322000Y318500D03*
X1317000Y336000D03*
X1384500Y331500D03*
G54D51*
X1379862Y108465D03*
Y119095D03*
G54D38*
X121890Y269528D03*
X131890D03*
X141890D03*
X1346396Y21656D03*
X1338526D03*
X1346396Y29526D03*
X1338526D03*
X1362146Y21656D03*
X1354271D03*
X1362146Y29526D03*
X1354271D03*
X1377896Y21656D03*
X1370021D03*
X1377896Y29526D03*
X1370021D03*
X1385766Y21656D03*
Y29526D03*
G54D55*
X1224016Y386221D03*
G54D49*
X867914Y290355D03*
X863974Y298230D03*
X871849Y308070D03*
X867914Y315945D03*
X863974Y308070D03*
G54D33*
X35435Y373228D03*
X82675D03*
X180118Y739409D03*
X200118Y729409D03*
X190118D03*
X200118Y739409D03*
X190118D03*
X210118Y729409D03*
Y739409D03*
X230118Y729409D03*
Y739409D03*
X220118D03*
X250118Y729409D03*
X240118D03*
X250118Y739409D03*
X240118D03*
X260118Y729409D03*
Y739409D03*
X270118Y729409D03*
Y739409D03*
G54D32*
X21220Y373228D03*
X96890D03*
X157480Y283071D03*
X220472D03*
G54D46*
X1057086Y43267D03*
X1084646D03*
G54D54*
X1227165Y411417D03*
G54D44*
X585315Y44134D03*
X654527D03*
G54D45*
X1045000Y32598D03*
X1096732D03*
G54D34*
X270078Y92125D03*
X490944Y79921D03*
X743897Y410629D03*
X1305117Y87548D03*
X1376968Y147243D03*
Y216535D03*
G54D48*
X355708Y96456D03*
G54D35*
X19272Y337795D03*
Y396850D03*
X98838Y337795D03*
Y396850D03*
%LPD*%
G75*
G54D10*
X8590Y318590D03*
X4500Y329297D03*
Y349297D03*
Y369297D03*
Y389297D03*
Y409297D03*
Y429297D03*
Y449297D03*
Y469297D03*
Y489297D03*
Y509297D03*
Y529297D03*
Y549297D03*
Y569297D03*
Y589297D03*
Y609297D03*
Y629297D03*
Y649297D03*
Y669297D03*
Y689297D03*
Y709297D03*
Y729297D03*
Y749297D03*
Y769297D03*
Y789297D03*
Y809297D03*
Y829297D03*
Y869297D03*
Y889297D03*
Y909297D03*
Y929297D03*
Y949297D03*
Y969297D03*
X20000Y380000D03*
Y440000D03*
Y460000D03*
Y480000D03*
Y500000D03*
X25000Y980000D03*
X45000D03*
X55000Y975000D03*
X65000Y980000D03*
X75000Y975000D03*
X95000D03*
X146364Y296000D03*
X140000Y720000D03*
Y740000D03*
X156500Y939500D03*
X168000Y575000D03*
Y580000D03*
X180000Y760000D03*
X207100Y703600D03*
X206000Y982000D03*
X222000Y703500D03*
X220000Y760000D03*
X226000Y982000D03*
X246000D03*
X261500Y188900D03*
X256300Y188800D03*
X258800Y184200D03*
X261400Y179800D03*
X255800Y179600D03*
X260000Y260000D03*
Y760000D03*
X261178Y981040D03*
X281800Y183700D03*
Y188500D03*
X281900Y178500D03*
X296000Y105000D03*
X285800Y180800D03*
X285600Y186100D03*
X285678Y995500D03*
X293178D03*
X299500Y5500D03*
X306000Y105000D03*
X301000D03*
X311500Y272000D03*
X301178Y995500D03*
X309678D03*
X321000Y29000D03*
Y33500D03*
Y38000D03*
Y57000D03*
Y52500D03*
Y48000D03*
Y42500D03*
Y61500D03*
X316000Y271500D03*
X324678Y995500D03*
X317178D03*
X337500Y102000D03*
X341178Y996000D03*
X332678Y995500D03*
X362500Y608500D03*
X355500D03*
Y614000D03*
X362500D03*
X358268Y995500D03*
X348678Y996000D03*
X370500Y72100D03*
X376500Y608500D03*
X369500D03*
Y614000D03*
X376500D03*
X378500Y812000D03*
Y824500D03*
X377953Y995725D03*
X393800Y25100D03*
X389300Y20100D03*
X393800D03*
X384800Y25100D03*
X389300D03*
X384800Y20100D03*
X391000Y35500D03*
X395500D03*
X393900Y30400D03*
X389400D03*
X384900D03*
X389763Y996085D03*
X398300Y20100D03*
Y25100D03*
X400000Y35500D03*
X398400Y30400D03*
X398000Y39500D03*
X406500Y713500D03*
X412000Y724000D03*
X409500Y775500D03*
X422500Y764500D03*
X445395Y317610D03*
X431000Y713500D03*
Y724000D03*
X435678Y996000D03*
X443178D03*
X458678D03*
X450178D03*
X477500Y715000D03*
X474178Y995500D03*
X466178Y996000D03*
X482429Y139000D03*
X491500Y715000D03*
X490500Y800000D03*
X495000Y883000D03*
X489678Y995500D03*
X482178D03*
X504500Y715000D03*
X502500Y800000D03*
X501000Y876000D03*
X499000Y883000D03*
X505678Y995500D03*
X498178D03*
X526055Y548900D03*
X521178Y995500D03*
X513678D03*
X536678Y996000D03*
X530083Y995500D03*
X560000Y20000D03*
X560678Y996000D03*
X567500Y457500D03*
X563000Y453000D03*
X567500D03*
Y462000D03*
Y466500D03*
X563000Y457500D03*
Y462000D03*
Y466500D03*
X569178Y996000D03*
X576678D03*
X591000Y253500D03*
Y262500D03*
X586000Y267000D03*
Y262500D03*
X591000Y258000D03*
X593500Y648500D03*
Y659500D03*
Y654000D03*
X584678Y994500D03*
X595500Y253500D03*
Y258000D03*
X610500Y333000D03*
X606000Y341500D03*
X609000Y345500D03*
X601000Y543000D03*
X599500Y648500D03*
Y654000D03*
Y659500D03*
X604500Y714500D03*
X609500Y778500D03*
X603000D03*
Y785000D03*
X609000Y870000D03*
X604000Y877500D03*
X609211Y877611D03*
X598178Y983500D03*
X615000Y333000D03*
X620500D03*
X611500Y341500D03*
X613500Y345500D03*
X616500Y341500D03*
X621500D03*
X626500Y557350D03*
X616500Y714500D03*
X613500Y744500D03*
Y759000D03*
X620500Y848500D03*
X642000Y335000D03*
X639000Y332000D03*
X634000Y734500D03*
X633500Y749500D03*
X650000Y110000D03*
X645500Y481000D03*
X657500Y827000D03*
X674666Y82002D03*
X670998Y116010D03*
X660000Y120000D03*
X670522Y130200D03*
X673500Y334000D03*
X668000D03*
X662000D03*
X690966Y142028D03*
X685000Y150500D03*
X690500Y468000D03*
X701828Y129550D03*
X698500Y132500D03*
X704716Y156520D03*
X700216Y156368D03*
X705500Y352500D03*
X707000Y340500D03*
X694000Y483500D03*
X693500Y472000D03*
X694000Y492000D03*
Y500500D03*
Y507500D03*
Y514000D03*
X722716Y156520D03*
X718216D03*
X713716D03*
X709216D03*
X719500Y185600D03*
X730748Y99500D03*
X740000Y109534D03*
X732248Y140000D03*
X736000Y142000D03*
X727216Y156520D03*
X746716Y130238D03*
X750916Y130272D03*
X757000Y435500D03*
X752100Y435600D03*
X751500Y431000D03*
X756500D03*
X757802Y474000D03*
X760522Y116784D03*
X770000Y123500D03*
X761600Y435600D03*
X761500Y431000D03*
X766000D03*
X773000Y917000D03*
Y921500D03*
Y927000D03*
X767500D03*
X800000Y100000D03*
X800500Y977500D03*
X794500D03*
X800500Y982000D03*
X794500D03*
X810000Y120000D03*
X819000Y473000D03*
X820500Y754000D03*
Y765500D03*
X848600Y517100D03*
X843100Y517000D03*
X843200Y512800D03*
X843300Y507900D03*
X848800Y508000D03*
X848700Y512900D03*
X854500Y778000D03*
X850000D03*
X854500Y783000D03*
X850000D03*
X870000Y160000D03*
X879736Y290000D03*
X875500Y290500D03*
X878500Y294178D03*
X889000Y617000D03*
X890000Y140000D03*
X895000Y617500D03*
X910000Y160000D03*
X915000Y805000D03*
Y825000D03*
Y845000D03*
Y865000D03*
Y885000D03*
Y905000D03*
Y925000D03*
Y945000D03*
Y965000D03*
X930500Y536500D03*
X943500Y488000D03*
X963500D03*
Y536500D03*
X981000Y386500D03*
X985000Y388000D03*
X980500Y391000D03*
X984500Y392500D03*
X1007000Y12000D03*
X1032000Y82500D03*
Y90000D03*
Y97000D03*
Y103500D03*
Y110000D03*
X1035000Y970000D03*
X1053000Y228000D03*
X1057000Y229500D03*
X1056716Y224500D03*
X1060000Y929500D03*
X1055000Y970000D03*
X1079000Y434000D03*
X1085000D03*
X1079100Y429000D03*
X1075000Y970000D03*
X1100000Y180000D03*
X1106600Y753000D03*
X1114500Y855500D03*
X1119000D03*
X1105000Y970000D03*
X1125000D03*
X1137000Y890000D03*
X1144500D03*
X1152000D03*
X1145000Y970000D03*
X1161500Y222000D03*
X1166500D03*
X1160500Y242000D03*
Y246500D03*
X1165000Y242000D03*
Y246500D03*
X1158000Y890000D03*
X1164500D03*
X1171000Y222000D03*
X1176000D03*
X1169000Y398000D03*
X1171000Y394000D03*
X1173100Y499200D03*
X1175000Y970000D03*
X1199100Y226600D03*
X1194900D03*
X1195000Y422500D03*
X1194000Y484000D03*
X1189500D03*
X1194000Y488500D03*
X1189500D03*
Y492900D03*
X1194000Y493000D03*
X1188500Y500000D03*
X1195000Y970000D03*
X1204000Y206000D03*
X1208500Y207000D03*
X1204000Y210500D03*
Y215000D03*
X1207500Y225000D03*
X1203300Y226600D03*
X1217000Y537000D03*
X1216500Y710125D03*
X1215000Y970000D03*
X1249300Y166000D03*
X1240600Y167000D03*
X1240700Y171200D03*
X1240800Y179800D03*
X1240700Y175500D03*
Y184000D03*
X1246000Y263500D03*
X1263000Y717000D03*
X1330000Y428000D03*
X1331500Y432500D03*
X1358500Y346500D03*
Y351000D03*
X1354000D03*
Y346500D03*
X1354500Y480500D03*
Y475000D03*
X1360500D03*
Y480500D03*
X1354500Y486500D03*
X1360500D03*
X1354500Y703500D03*
X1371500Y254000D03*
X1366000D03*
X1371500Y264000D03*
X1366000D03*
X1371500Y259500D03*
X1366000D03*
X1378500Y370000D03*
Y365000D03*
Y360000D03*
X1377000Y384000D03*
Y379000D03*
X1378500Y374500D03*
X1377000Y390000D03*
X1374500Y395000D03*
Y402000D03*
X1372500Y415000D03*
G54D11*
X19272Y337795D03*
Y396850D03*
X98838Y337795D03*
Y396850D03*
G54D20*
X1258504Y329331D03*
Y368701D03*
G54D30*
G01X180118Y729409D02*
X198459Y711068D01*
X636426D01*
X665408Y740050D01*
X860886D01*
X860986Y739950D01*
X878050D01*
X881000Y737000D01*
Y736500D01*
G01X390000Y13500D02*
X411315D01*
X413315Y15500D01*
X452000D01*
X493000Y56500D01*
X540287D01*
X576393Y92606D01*
X644062D01*
X667584Y69084D01*
Y65416D01*
X687500Y45500D01*
X843000D01*
X862500Y65000D01*
G01X873000Y68500D02*
X862500D01*
X843500Y49500D01*
X751450D01*
X750000Y48050D01*
X688450D01*
X680500Y56000D01*
Y57280D01*
X676500Y61280D01*
Y62290D01*
X670500Y68290D01*
Y70500D01*
X645855Y95145D01*
X574228D01*
X538500Y59417D01*
X491232D01*
X449657Y17842D01*
X410842D01*
X409500Y16500D01*
X388000D01*
X385000Y13500D01*
G01X873500Y61500D02*
X871000D01*
X852700Y43200D01*
X679800D01*
X661200Y61800D01*
Y71705D01*
X644405Y88500D01*
X574692D01*
X540992Y54800D01*
X540850D01*
X540550Y54500D01*
X495500D01*
X454500Y13500D01*
X419500D01*
X414000Y8000D01*
G01X874000Y56000D02*
X859500Y41500D01*
X677000D01*
X659500Y59000D01*
Y71000D01*
X644000Y86500D01*
X578500D01*
X543500Y51500D01*
X496000D01*
X456000Y11500D01*
X441000D01*
X438500Y9000D01*
G01X947500Y153000D02*
X948000Y153500D01*
Y171807D01*
X960693Y184500D01*
X973258D01*
X977407Y188649D01*
Y271512D01*
X1040450Y334555D01*
Y400052D01*
X1001002Y439500D01*
X984975D01*
X982925Y437450D01*
X934600D01*
X907000Y465050D01*
G54D21*
X1338526Y29526D03*
G54D12*
X8200Y857700D03*
X8000Y853500D03*
X50395Y384679D03*
X40945Y384710D03*
X48820Y412435D03*
X39370Y412673D03*
X52000Y655500D03*
X40054Y823970D03*
X36004Y839500D03*
X44500Y851500D03*
X49000Y861500D03*
X37232Y877242D03*
X42554Y891720D03*
X37758Y884674D03*
X40304Y887220D03*
X38804Y906220D03*
X41500Y941500D03*
X46500Y944500D03*
X59840Y384679D03*
X67715Y412518D03*
X58270Y412485D03*
X60304Y663220D03*
X64304Y698720D03*
X63304Y706720D03*
X62704Y739620D03*
X64272Y736004D03*
X55304Y746220D03*
X65804Y835720D03*
X78740Y384915D03*
X69290Y384865D03*
X77165Y412590D03*
X76804Y662720D03*
X73804Y699720D03*
X81304Y710220D03*
X76272Y762504D03*
X77804Y773720D03*
X71804Y789720D03*
X82804Y794920D03*
X73772Y822004D03*
X69804Y835720D03*
X83838Y848133D03*
X76804Y847720D03*
X89804Y669720D03*
X97737Y698653D03*
X96060Y762476D03*
X100804Y774720D03*
X99804Y799720D03*
X85204Y798220D03*
X85804Y816220D03*
X92304Y835720D03*
X87804D03*
X112654Y314453D03*
X111907Y698617D03*
X115804Y798720D03*
X105804Y943220D03*
X127654Y293453D03*
X131500Y324000D03*
X122906Y331953D03*
X132500Y547000D03*
Y559600D03*
Y556000D03*
Y551500D03*
X122500Y845500D03*
X128000Y870500D03*
X143500Y710500D03*
X141054Y795820D03*
X150225Y790412D03*
X146304Y804220D03*
X146500Y808220D03*
X162595Y296709D03*
X159774Y320709D03*
X160000Y465500D03*
X153050Y486500D03*
X154625Y550290D03*
X163305Y554750D03*
X166000Y662500D03*
X157750Y662250D03*
X166500Y650500D03*
X162500Y670000D03*
X163000Y710500D03*
X150900Y812500D03*
X154500D03*
X152500Y840000D03*
X157500Y867500D03*
X172285Y296964D03*
X181889Y297303D03*
X183374Y328709D03*
X171874D03*
X171295Y320709D03*
X180315Y321209D03*
X171500Y478699D03*
X177493Y533493D03*
X174000Y830500D03*
X170500Y835500D03*
X172000Y868000D03*
X168400D03*
X183000Y865750D03*
X197245Y296571D03*
X196063Y319209D03*
X192874Y326209D03*
Y337907D03*
X189000Y347600D03*
X187300Y457300D03*
X191800D03*
X198500Y563000D03*
X198000Y785000D03*
X191875Y803125D03*
X207086Y297418D03*
X205511Y320709D03*
X214960Y321044D03*
X204500Y470000D03*
X203000Y564500D03*
X201000Y625500D03*
X212500Y786000D03*
X204500Y817500D03*
X215250Y833750D03*
X204000Y862000D03*
X217295Y296709D03*
X229055Y497000D03*
X216500Y516000D03*
X228319Y524798D03*
X223500Y825500D03*
X228000Y825000D03*
X232000D03*
X242003Y506327D03*
X234755Y509700D03*
X245205Y504679D03*
X246613Y501365D03*
X237055Y513500D03*
X234185Y527138D03*
X248855Y532300D03*
X239555Y519500D03*
X247500Y829500D03*
X259055Y500500D03*
X260288Y514589D03*
X250055Y510800D03*
X256055Y531016D03*
X260555Y525500D03*
X253679Y523137D03*
X260605Y519245D03*
X263555Y534500D03*
X261255Y549000D03*
X265455Y544853D03*
X252055Y548760D03*
X257555Y549000D03*
X258500Y608500D03*
Y613500D03*
X253500Y608500D03*
X253555Y613500D03*
X268300Y219800D03*
X272571Y541150D03*
X278367Y535140D03*
X269555Y536000D03*
X271451Y544616D03*
X270000Y870000D03*
Y865500D03*
X276500Y888500D03*
X280500Y955000D03*
X278050Y958500D03*
X294500Y98500D03*
X297929Y332000D03*
Y336000D03*
X293929Y342000D03*
X292525Y498780D03*
X292045Y504897D03*
X299300Y84200D03*
X299831Y144328D03*
X303677D03*
X313402Y156000D03*
X305852Y163800D03*
X309698D03*
X307500Y299000D03*
X305055Y472500D03*
X302555Y476000D03*
X324500Y6000D03*
Y10500D03*
X316900Y65900D03*
X320500Y66000D03*
X317660Y96400D03*
X326422Y152507D03*
Y148944D03*
X317248Y156000D03*
X326000Y292500D03*
X327000Y308000D03*
X331000Y308018D03*
X330555Y467500D03*
X325873Y477006D03*
X325854Y480606D03*
X315725Y549790D03*
X329695Y534650D03*
X321500Y688000D03*
X336700Y4300D03*
X341200D03*
X346000Y4400D03*
X333000Y90500D03*
X343000Y89000D03*
X337500Y84250D03*
X344429Y312000D03*
X341500Y309500D03*
X343929Y320700D03*
X342500Y340000D03*
X338985Y467405D03*
X347213Y546700D03*
X345500Y556500D03*
X339888Y586388D03*
X346402Y653004D03*
X335500Y868000D03*
X332129Y889371D03*
X331829Y885500D03*
X338000Y942000D03*
X339500Y960000D03*
X355000Y4400D03*
X350500D03*
X360400D03*
X362500Y286000D03*
X351929Y332500D03*
X349575Y479503D03*
X349815Y475550D03*
X358797Y532258D03*
X354055Y534000D03*
X362555Y534500D03*
X360500Y588500D03*
X350000Y652878D03*
X362210Y876200D03*
X354000Y960000D03*
X363614Y971524D03*
X361000Y974000D03*
X360024Y979100D03*
X364900Y4400D03*
X369400D03*
X366600Y285800D03*
X370275Y413540D03*
X369555Y417500D03*
X373555Y482500D03*
X379000Y531000D03*
X371000Y866500D03*
X376041Y866041D03*
X372300Y918749D03*
X364396Y980109D03*
X366878Y977500D03*
X369200Y980252D03*
X372500Y977918D03*
X377464Y987493D03*
X377250Y982250D03*
X390000Y13500D03*
X385000D03*
X395500Y237000D03*
X388000Y233500D03*
X388149Y229780D03*
X382455Y331870D03*
X393055Y451000D03*
Y447400D03*
X385463Y450948D03*
X396055Y456500D03*
X388885Y471100D03*
X381500Y534000D03*
X384046Y536546D03*
X391000Y866500D03*
X389838Y942300D03*
X388500Y955250D03*
X390000Y946500D03*
X397900Y231800D03*
X403255Y425950D03*
X404500Y877300D03*
X401500Y994500D03*
X414000Y8000D03*
X418192Y114237D03*
X421000Y231500D03*
X429500Y311000D03*
X425178Y798000D03*
X418278Y828000D03*
Y840000D03*
X418500Y857500D03*
X418278Y854000D03*
Y846500D03*
X425000Y994500D03*
X440000Y5000D03*
X438500Y9000D03*
X430540Y108750D03*
X432178Y798000D03*
X438178Y798500D03*
X444678Y798400D03*
X442278Y846000D03*
X430500Y962000D03*
X460000Y5000D03*
X456000Y243500D03*
X460000D03*
X461100Y260050D03*
X459055Y263500D03*
X456178Y798000D03*
X452978Y805400D03*
X455278Y846000D03*
X451278D03*
X459278D03*
X466700Y259400D03*
X464055Y256500D03*
X475678Y798500D03*
X463178D03*
X469178D03*
X467278Y846000D03*
X485000Y5000D03*
X488500Y114200D03*
X491257Y315952D03*
X495103D03*
X487612Y318606D03*
X488000Y904500D03*
X483500Y907500D03*
X499390Y153500D03*
X503500D03*
X508500Y320000D03*
X504453Y314200D03*
X500607D03*
X508100Y605500D03*
X506000Y610000D03*
X497778Y843000D03*
Y838500D03*
Y847000D03*
X515000Y5000D03*
X521700Y114000D03*
X513000Y156500D03*
X512000Y320000D03*
X533000Y153800D03*
X531590Y297620D03*
X534500Y295500D03*
X528500Y310000D03*
X534629Y311171D03*
X545000Y5000D03*
X548000Y369500D03*
X559500Y604500D03*
X575000Y5000D03*
X564215Y369339D03*
X566430Y366500D03*
X569555Y364000D03*
X619876Y195000D03*
X622500Y608500D03*
X641500Y449500D03*
X640500Y444500D03*
X641625Y465375D03*
X656162Y472338D03*
X654500Y494000D03*
X663500Y452000D03*
X672500D03*
X663500Y456000D03*
Y460500D03*
X667500Y454000D03*
Y458500D03*
X672500Y456000D03*
Y460500D03*
X673300Y579000D03*
X669000D03*
X663500Y610500D03*
X674688Y696751D03*
X672000Y967750D03*
X667000Y969700D03*
X666750Y961550D03*
X685000Y5000D03*
X685519Y55019D03*
X684861Y58584D03*
X686000Y62000D03*
X684197Y74703D03*
X681000Y452000D03*
Y456000D03*
Y460500D03*
X676500Y454000D03*
Y458500D03*
X690000Y460500D03*
X688500Y606000D03*
X683000Y603950D03*
X680000Y640000D03*
X691000Y704500D03*
X677500Y699000D03*
X687968Y755284D03*
X691300Y807300D03*
X679000Y865050D03*
X676500Y967750D03*
X695000Y20000D03*
X706716Y82448D03*
X698818Y759350D03*
X715000Y5000D03*
X725000Y20000D03*
X716034Y53966D03*
X716466Y65466D03*
X711216Y82402D03*
X720216Y82138D03*
X721200Y205800D03*
X720700Y564200D03*
X717036Y563783D03*
X709750Y585200D03*
X722000Y808500D03*
X740500Y75000D03*
X733498Y180750D03*
X733000Y193000D03*
X732500Y485500D03*
X730000Y536500D03*
X733500Y568500D03*
X729900D03*
X741500Y582450D03*
X737000Y583640D03*
X733268Y757984D03*
X733000Y969700D03*
X745000Y5000D03*
X755000Y20000D03*
X754500Y67500D03*
X757200Y103100D03*
X745500Y145000D03*
X749750Y454000D03*
X755000Y727500D03*
X757500Y743500D03*
X757000Y896400D03*
X749500Y974300D03*
X770500Y136000D03*
X770900Y144300D03*
X765116Y187659D03*
X758500Y457000D03*
X774500Y489500D03*
X760500D03*
X766000Y635000D03*
X763000Y648000D03*
X767000Y648500D03*
X768000Y728000D03*
X775000Y5000D03*
X785000Y20000D03*
X789500Y235837D03*
X779000Y458000D03*
X786500Y575688D03*
X786032Y570468D03*
X783500Y649000D03*
X782750Y845750D03*
X785500Y969700D03*
X805000Y5000D03*
X798000Y706000D03*
X815000Y20000D03*
X823500Y556500D03*
X815900Y564000D03*
X819500D03*
X814000Y849500D03*
X810000Y980000D03*
X835000Y5000D03*
X826198Y239950D03*
X833500Y613000D03*
X835000Y719000D03*
X826500Y743000D03*
X824560Y868560D03*
X840000Y980000D03*
X850000Y20000D03*
X850540Y346070D03*
X849500Y622000D03*
X852600Y868500D03*
X865000Y5000D03*
X873000Y68500D03*
X870100Y237500D03*
X860400Y231000D03*
X870500Y448000D03*
X857500Y485500D03*
X859500Y629500D03*
X860718Y683684D03*
X870000Y980000D03*
X880000Y20000D03*
X877860Y316330D03*
X874910Y360160D03*
X879510Y355410D03*
X876000Y435500D03*
X877000Y479500D03*
X895000Y5000D03*
X899000Y312500D03*
X898000Y316000D03*
X903480Y324230D03*
X893500Y427000D03*
X903075Y472000D03*
X900000Y980000D03*
X910000Y20000D03*
X907000Y465050D03*
X917000Y752500D03*
X925000Y5000D03*
X923000Y51500D03*
X924465Y388465D03*
X937000Y489000D03*
X935400Y597300D03*
X955000Y5000D03*
X940000Y20000D03*
X953500Y348927D03*
X944000Y434000D03*
X970000Y20000D03*
X959500Y351688D03*
X964000Y354000D03*
X961700Y477500D03*
X957500Y585500D03*
X961500D03*
X970750Y703000D03*
X985000Y5000D03*
X982075Y439500D03*
X977000Y547500D03*
X982500Y549500D03*
X978000Y554000D03*
X975000Y701000D03*
X1000000Y20000D03*
X989000Y66500D03*
X988900Y434800D03*
X990500Y536500D03*
X998500Y591500D03*
X989000Y659500D03*
Y757150D03*
X1015000Y5000D03*
X1012000Y43000D03*
X1020500Y142000D03*
X1014000Y487000D03*
X1008500Y533400D03*
X1013500Y559000D03*
X1016900Y561000D03*
X1010000Y980000D03*
X1033500Y118000D03*
X1031524Y218476D03*
X1033900Y225500D03*
X1027426Y346500D03*
X1023000Y347000D03*
X1031000Y348500D03*
Y355950D03*
X1030000Y403500D03*
X1036500Y581500D03*
X1035000Y594500D03*
X1023500Y727000D03*
X1037000Y734000D03*
X1024387Y738230D03*
X1035000Y800000D03*
Y804500D03*
X1027716Y914784D03*
X1032200Y921500D03*
X1045000Y5000D03*
X1037500Y225500D03*
X1040000Y579000D03*
X1038000Y604000D03*
X1053500Y620500D03*
X1045500Y639500D03*
X1052500Y693000D03*
X1052678Y704084D03*
X1038500Y706500D03*
X1052500Y709000D03*
Y700000D03*
X1052648Y712724D03*
X1040208Y745020D03*
X1052500Y773350D03*
X1044000Y763940D03*
X1040000Y980000D03*
X1060000Y20000D03*
X1064000Y80000D03*
X1055500D03*
X1059500D03*
X1068000D03*
Y76000D03*
X1064000D03*
X1059500D03*
X1055500D03*
X1068500Y118500D03*
X1070000Y650725D03*
X1058350Y681450D03*
X1054500Y697000D03*
X1059800Y719740D03*
X1063000Y780000D03*
X1075000Y5000D03*
X1071000Y71000D03*
X1077250Y102000D03*
X1077500Y97000D03*
Y107500D03*
X1078500Y464000D03*
X1080000Y520000D03*
X1081000Y548000D03*
Y544400D03*
X1084599Y544520D03*
X1086000Y556000D03*
X1073384Y722384D03*
X1077000Y943075D03*
X1083200Y956500D03*
X1070000Y980000D03*
X1090000Y20000D03*
X1088000Y85500D03*
X1098000Y126500D03*
X1093894D03*
X1090028D03*
X1091425Y551425D03*
X1093500Y640000D03*
X1094500Y657500D03*
X1091000Y692519D03*
X1089000Y867284D03*
X1099623Y869123D03*
X1097423Y906546D03*
X1093500Y905500D03*
X1100000Y980000D03*
X1105000Y5000D03*
Y15000D03*
Y75000D03*
Y105000D03*
Y135000D03*
X1110318Y275600D03*
X1114883Y591925D03*
X1111500Y718500D03*
X1107000Y763000D03*
X1118034Y847034D03*
X1113768D03*
X1116468Y870284D03*
Y874284D03*
Y865784D03*
X1112468Y870284D03*
X1114500Y886000D03*
X1103000Y888300D03*
X1118500Y886000D03*
X1123000Y250500D03*
X1128000Y288500D03*
X1132300Y288800D03*
X1130000Y361500D03*
X1124327Y465391D03*
X1123500Y521500D03*
X1128149Y525261D03*
X1130928Y527550D03*
X1119487Y588088D03*
X1122353Y590268D03*
X1126000Y627329D03*
X1131000Y631000D03*
X1121500Y621600D03*
X1130490Y627436D03*
X1125041Y631000D03*
X1135468Y854032D03*
X1120468Y870284D03*
X1131275Y867725D03*
X1130000Y980000D03*
X1146500Y267000D03*
X1146000Y258500D03*
X1151000Y264500D03*
X1146500Y275500D03*
X1136100Y288900D03*
X1143500Y542000D03*
X1147500D03*
X1139632Y594441D03*
X1140500Y589000D03*
X1162468Y257968D03*
X1153700Y267700D03*
X1166000Y290000D03*
X1157700Y368500D03*
X1155400Y371500D03*
X1168000Y390250D03*
X1166500Y415500D03*
X1155500Y450758D03*
Y446892D03*
X1164500Y628723D03*
X1159075Y630600D03*
X1154847Y630908D03*
X1164500Y857500D03*
X1162000Y960625D03*
X1155000Y980000D03*
X1177500Y290000D03*
X1184000Y351500D03*
X1182000Y357000D03*
X1174400Y356500D03*
X1178000D03*
X1173500Y554000D03*
X1183000Y628000D03*
X1177100Y624750D03*
X1184500Y749500D03*
Y772782D03*
X1173200Y789500D03*
X1169000Y856000D03*
X1181500Y949000D03*
X1196334Y290561D03*
X1185283Y290513D03*
X1198000Y348000D03*
X1192000Y344500D03*
X1197000Y372500D03*
X1187500Y411000D03*
X1197000Y409500D03*
X1189000Y421500D03*
X1195000Y428000D03*
X1197675Y533125D03*
X1191000Y528000D03*
X1189000Y533825D03*
X1194564Y530936D03*
X1185500Y548075D03*
X1200500Y547925D03*
X1186000Y615500D03*
X1197500Y665500D03*
X1199551Y683968D03*
X1195937Y683849D03*
X1196500Y736687D03*
X1199500Y743500D03*
X1188500Y773000D03*
X1190000Y767500D03*
X1188875Y856625D03*
X1185000Y980000D03*
X1211500Y5500D03*
Y35500D03*
Y65500D03*
Y85500D03*
Y107500D03*
Y137500D03*
X1202177Y260000D03*
X1208500Y283500D03*
X1208000Y271499D03*
Y297638D03*
Y309000D03*
X1206500Y330000D03*
X1208500Y321500D03*
X1203500Y345000D03*
X1208500Y346400D03*
Y359000D03*
X1210800Y379700D03*
X1208000Y371000D03*
X1212500Y436000D03*
X1217000Y452500D03*
X1209500Y514000D03*
X1213100D03*
X1214450Y509000D03*
X1206400Y536800D03*
X1210000D03*
X1203181Y683968D03*
X1206781Y684003D03*
X1213598Y699164D03*
X1204000Y862000D03*
X1215000Y980000D03*
X1227500Y500500D03*
Y504246D03*
X1220500Y513000D03*
X1221500Y539500D03*
X1229000Y716000D03*
Y719600D03*
Y740000D03*
X1230219Y747469D03*
X1232000Y738000D03*
X1234000Y747500D03*
X1221000Y764750D03*
X1223000Y826500D03*
X1229807Y847000D03*
X1235500Y5000D03*
X1239000Y190500D03*
X1240000Y209449D03*
X1239000Y251500D03*
X1241777Y265700D03*
X1241377Y274900D03*
X1238500Y290000D03*
X1239000Y302437D03*
X1238500Y316500D03*
Y325985D03*
X1239000Y338900D03*
Y352800D03*
X1239500Y366000D03*
X1234177Y379500D03*
X1250000Y422000D03*
X1243000Y446650D03*
X1250450Y462000D03*
X1247800Y472750D03*
X1249251Y528688D03*
X1250500Y567000D03*
X1241000Y631500D03*
X1237500Y675500D03*
X1235000Y682000D03*
X1244371Y733129D03*
X1236500Y737925D03*
X1243000Y743000D03*
X1240016Y761500D03*
X1238000Y764500D03*
X1238047Y791953D03*
X1240045Y788957D03*
X1241984Y796000D03*
X1243953Y789000D03*
X1240660Y829000D03*
X1235258Y820758D03*
X1245000Y980000D03*
X1257000Y33000D03*
X1263000Y278500D03*
X1257468Y478500D03*
X1253000Y511000D03*
X1251500Y531500D03*
X1260500Y546400D03*
X1258000Y555400D03*
X1266500Y617500D03*
X1265500Y652500D03*
X1263121Y678621D03*
X1253500Y778465D03*
X1257950Y809250D03*
X1268000Y5000D03*
X1279500Y150500D03*
X1274500Y606000D03*
X1278500Y603500D03*
X1271000Y617500D03*
X1268805Y655405D03*
X1273702Y667662D03*
X1275885Y670525D03*
X1267500Y675000D03*
Y684878D03*
X1279000Y746575D03*
X1275000Y980000D03*
X1290874Y34376D03*
X1299500Y236000D03*
X1285700Y529700D03*
X1291300Y540900D03*
X1294000Y587500D03*
X1288335Y594048D03*
X1287482Y590500D03*
X1293500Y593000D03*
X1285557Y585000D03*
X1289570Y597430D03*
X1299000Y641500D03*
X1296000Y638500D03*
X1289500Y669000D03*
X1298034Y907034D03*
X1307500Y5000D03*
X1306000Y43000D03*
X1309500Y51000D03*
X1306000Y329000D03*
X1311000Y435000D03*
X1302000Y475000D03*
X1302500Y559500D03*
X1307000Y573412D03*
X1310500Y625000D03*
X1310425Y660062D03*
X1311100Y656400D03*
X1311300Y687500D03*
X1313500Y710000D03*
X1305000Y739750D03*
X1308100Y748200D03*
X1312500Y838000D03*
X1312000Y850500D03*
X1307468Y884532D03*
X1300000Y980000D03*
X1331000Y120000D03*
X1325950Y599000D03*
X1323500Y702000D03*
X1322000Y705500D03*
X1316500Y839000D03*
X1317000Y850500D03*
X1318113Y846371D03*
X1321466Y907034D03*
X1330000Y980000D03*
X1337500Y5000D03*
X1333100Y58600D03*
X1347000Y88000D03*
X1347500Y116000D03*
X1344000Y434500D03*
X1340200D03*
Y438300D03*
X1343900Y438500D03*
X1343000Y466500D03*
X1346617Y626912D03*
X1342367Y627662D03*
X1334500Y636000D03*
X1354500Y276000D03*
X1358500Y288916D03*
X1355500Y556500D03*
X1360817Y557812D03*
X1353117Y610412D03*
X1363100Y627000D03*
X1349817Y628612D03*
X1360000Y980000D03*
X1369720Y106365D03*
X1375500Y328000D03*
X1368000Y450500D03*
X1374500Y462800D03*
X1369617Y557012D03*
X1394122Y5878D03*
X1390004Y106000D03*
G54D31*
G01X1171500Y720000D02*
X1171774Y719726D01*
Y716772D01*
X1173347Y715199D01*
Y714350D01*
G01X1127438Y674944D02*
X1127474Y674980D01*
X1134630D01*
X1136150Y676500D01*
G01X1123905Y687547D02*
X1123971D01*
X1124004Y687580D01*
X1130002D01*
X1130883Y686700D01*
X1131579Y686004D01*
X1132440D01*
G01X1130358Y681194D02*
X1130387Y681223D01*
X1134075D01*
X1135594Y679704D01*
G01X1132440Y701714D02*
X1130865Y703289D01*
X1120111D01*
X1120030Y703370D01*
G01X1122280Y706670D02*
X1122497Y706453D01*
X1130857D01*
X1132406Y704904D01*
G01X1133022Y708061D02*
X1131585Y709498D01*
X1130071D01*
X1129938Y709631D01*
X1122932D01*
X1122633Y709930D01*
G01X1129277Y711210D02*
Y711243D01*
X1127727Y712793D01*
X1123010D01*
G01X1137182Y662182D02*
Y664590D01*
X1138708Y666116D01*
Y667113D01*
G01X1165330Y659370D02*
X1165521Y659561D01*
Y665499D01*
X1163944Y667076D01*
G01X1163914Y673352D02*
Y672506D01*
X1165492Y670928D01*
Y670008D01*
X1166833Y668667D01*
X1167687D01*
X1168609Y667745D01*
Y666891D01*
X1168617Y666883D01*
Y666447D01*
X1169300Y665764D01*
Y663120D01*
G01X1186026Y687872D02*
X1185725Y687571D01*
X1180366D01*
X1180331Y687536D01*
X1179025D01*
X1179016Y687545D01*
X1175045D01*
X1173474Y685974D01*
X1173392D01*
G54D22*
X1367067Y60039D03*
Y96260D03*
X1392657Y60039D03*
Y96260D03*
G54D13*
G01X-245081Y-422119D02*
G02I-12000J0D01*
G01X-250231D02*
G02I-6850J0D01*
G01X-241081D02*
X-273081D01*
G01X-257081Y-438119D02*
Y-406119D01*
G01X-241081Y-438119D02*
Y-518119D01*
G01D02*
X1034819D01*
G01X-241081Y-473619D02*
X1034819D01*
G01X-241081Y-438119D02*
X1034819D01*
G01X12120Y337795D02*
X19272D01*
G01X12120Y396850D02*
X19272D01*
G01X44500Y851500D02*
X42000Y849000D01*
X12500D01*
X8000Y853500D01*
G01X19272Y330643D02*
Y337795D01*
G01D02*
Y344947D01*
G01Y337795D02*
X26424D01*
G01X19272Y389698D02*
Y396850D01*
G01D02*
Y404002D01*
G01Y396850D02*
X26424D01*
G01X65804Y835720D02*
X59924Y841600D01*
X56100D01*
X46200Y851500D01*
X44500D01*
G01X156500Y939500D02*
Y934900D01*
X121820Y900220D01*
X54220D01*
X45720Y891720D01*
X42554D01*
G01X98838Y330643D02*
Y337795D01*
G01D02*
Y344947D01*
G01X91686Y337795D02*
X98838D01*
G01D02*
X105990D01*
G01X98838Y389698D02*
Y396850D01*
G01D02*
Y404002D01*
G01X91686Y396850D02*
X98838D01*
G01D02*
X105990D01*
G01X143500Y710500D02*
X130584D01*
X89804Y669720D01*
G01X152500Y840000D02*
X150500Y838000D01*
X94584D01*
X92304Y835720D01*
G01X109000Y844220D02*
X109780Y845000D01*
X122000D01*
X122500Y845500D01*
G01X128000Y544050D02*
Y404000D01*
X118174Y394174D01*
Y316826D01*
X127000Y308000D01*
Y294107D01*
X127654Y293453D01*
G01X204500Y470000D02*
Y450500D01*
X177500Y423500D01*
Y358016D01*
X164984Y345500D01*
X149110D01*
X128800Y325190D01*
Y312381D01*
X133681Y307500D01*
X134864D01*
X146364Y296000D01*
G01X160000Y465500D02*
X149000Y476500D01*
Y545500D01*
X153790Y550290D01*
X154625D01*
G01X163000Y710500D02*
X143500D01*
G01X153937Y235196D02*
Y238898D01*
G01Y243070D02*
Y246772D01*
G01D02*
Y250474D01*
G01X150235Y246772D02*
X153937D01*
G01D02*
X157639D01*
G01X153937Y238898D02*
Y242600D01*
G01X150235Y238898D02*
X153937D01*
G01D02*
X157639D01*
G01X153937Y256849D02*
Y260551D01*
G01D02*
Y264253D01*
G01X150235Y260551D02*
X153937D01*
G01D02*
X157639D01*
G01X177493Y533493D02*
Y517793D01*
X166200Y506500D01*
G01X207100Y703600D02*
X169900D01*
X163000Y710500D01*
G01X190118Y734957D02*
Y739409D01*
G01D02*
Y743861D01*
G01X185666Y739409D02*
X190118D01*
G01D02*
X194570D01*
G01X195666D02*
X200118D01*
G01X215666D02*
X220118D01*
G01X210118Y734957D02*
Y739409D01*
G01D02*
Y743861D01*
G01X205666Y739409D02*
X210118D01*
G01D02*
X214570D01*
G01X200118Y734957D02*
Y739409D01*
G01D02*
Y743861D01*
G01Y739409D02*
X204570D01*
G01X224015Y234961D02*
Y238663D01*
G01X220313Y234961D02*
X224015D01*
G01D02*
X227717D01*
G01X224015Y243070D02*
Y246772D01*
G01D02*
Y250474D01*
G01X220313Y246772D02*
X224015D01*
G01D02*
X227717D01*
G01X224015Y256849D02*
Y260551D01*
G01D02*
Y264253D01*
G01X220313Y260551D02*
X224015D01*
G01D02*
X227717D01*
G01X253500Y707250D02*
X252750Y708000D01*
X226500D01*
X222000Y703500D01*
G01X230118Y724957D02*
Y729409D01*
G01D02*
Y733861D01*
G01X225666Y729409D02*
X230118D01*
G01D02*
X234570D01*
G01X220118Y734957D02*
Y739409D01*
G01D02*
Y743861D01*
G01Y739409D02*
X224570D01*
G01X230118Y734957D02*
Y739409D01*
G01D02*
Y743861D01*
G01X225666Y739409D02*
X230118D01*
G01D02*
X234570D01*
G01X247319Y-438119D02*
Y-518119D01*
G01X240118Y734957D02*
Y739409D01*
G01D02*
Y743861D01*
G01X235666Y739409D02*
X240118D01*
G01D02*
X244570D01*
G01X245666D02*
X250118D01*
G01X260118Y724957D02*
Y729409D01*
G01D02*
Y733861D01*
G01X255666Y729409D02*
X260118D01*
G01D02*
X264570D01*
G01X260118Y734957D02*
Y739409D01*
G01D02*
Y743861D01*
G01X255666Y739409D02*
X260118D01*
G01D02*
X264570D01*
G01X250118Y734957D02*
Y739409D01*
G01D02*
Y743861D01*
G01Y739409D02*
X254570D01*
G01X270118Y724957D02*
Y729409D01*
G01D02*
Y733861D01*
G01X265666Y729409D02*
X270118D01*
G01D02*
X274570D01*
G01X270118Y734957D02*
Y739409D01*
G01D02*
Y743861D01*
G01X265666Y739409D02*
X270118D01*
G01D02*
X274570D01*
G01X342500Y340000D02*
X341634Y339134D01*
X340232D01*
X338651Y337553D01*
Y335315D01*
X338733Y335233D01*
Y334767D01*
X345300Y328200D01*
X346048D01*
X348748Y325500D01*
X353625D01*
X370625Y308500D01*
X442000D01*
X448000Y314500D01*
G01X343929Y320700D02*
X352300D01*
X368000Y305000D01*
X441000D01*
G03X449864Y308671I1J12535D01*
G01X450345Y309153D01*
X474251Y333059D01*
Y339528D01*
X467914Y345865D01*
G01X384041Y170888D02*
X383522D01*
X380710Y173700D01*
Y182100D01*
X375447Y187363D01*
X373611D01*
X372206Y188768D01*
Y190604D01*
X371429Y191381D01*
Y203257D01*
G03X368429Y210500I-10243J0D01*
G01Y215327D01*
X382882Y229780D01*
X388149D01*
G01X384819Y-438119D02*
Y-518119D01*
G01X397900Y231800D02*
Y223900D01*
X396500Y222500D01*
Y217710D01*
X394355Y215565D01*
X394043Y215500D01*
X392385D01*
X389609Y212724D01*
Y189226D01*
X387992Y187609D01*
Y185619D01*
X389604Y184007D01*
Y170675D01*
X387205Y168276D01*
Y167715D01*
G01X384030Y177120D02*
Y182670D01*
X380918Y185782D01*
Y202989D01*
X386455Y208526D01*
Y223904D01*
X390649Y228098D01*
Y230851D01*
X388000Y233500D01*
G01X421000Y231500D02*
X417000D01*
X412500Y227000D01*
Y217000D01*
X414500Y215000D01*
X429000D01*
X431000Y213000D01*
Y209500D01*
X429000Y207500D01*
X423000D01*
X418727Y203227D01*
Y192902D01*
G01X428149Y161416D02*
Y161171D01*
X430304Y159016D01*
X438592D01*
X439998Y160422D01*
Y167248D01*
X442887Y170137D01*
X444877D01*
X447207Y167807D01*
Y139827D01*
X456934Y130100D01*
X458924D01*
X459724Y130900D01*
X470210D01*
X470310Y130800D01*
X472548D01*
X480748Y139000D01*
X482429D01*
G01X448000Y314500D02*
X449500D01*
G01X488500Y114200D02*
X488700Y114000D01*
X521700D01*
G01X499819Y-438119D02*
Y-518119D01*
G01X521700Y114000D02*
X571700Y164000D01*
X592500D01*
X614100Y185600D01*
X719500D01*
G01X559750Y264500D02*
X559500Y264250D01*
Y249508D01*
X518929Y208937D01*
Y162429D01*
X513000Y156500D01*
G01X526055Y548900D02*
X529100D01*
X531200Y551000D01*
X733181D01*
X733343Y550838D01*
X735581D01*
X735743Y551000D01*
X897635D01*
X925935Y522700D01*
X1013500D01*
X1014000Y522200D01*
X1064800D01*
X1075500Y511500D01*
X1103000D01*
X1119800Y494700D01*
X1177700D01*
X1182500Y499500D01*
X1188000D01*
X1188500Y500000D01*
G01X585315Y38832D02*
Y44134D01*
G01D02*
Y49436D01*
G01X580013Y44134D02*
X585315D01*
G01D02*
X590617D01*
G01X641500Y449500D02*
X641700Y449300D01*
X750800D01*
X758500Y457000D01*
G01X654527Y38832D02*
Y44134D01*
G01D02*
Y49436D01*
G01X649225Y44134D02*
X654527D01*
G01D02*
X659829D01*
G01X667319Y-438119D02*
Y-518119D01*
G01X710100Y182700D02*
X685000Y157600D01*
Y150500D01*
G01X877000Y479500D02*
X876000Y478500D01*
X836000D01*
X829000Y485500D01*
X797000D01*
X791500Y480000D01*
X782500D01*
X778500Y484000D01*
X756781D01*
X730000Y510781D01*
Y536500D01*
G01X961700Y477500D02*
X946200Y493000D01*
X764000D01*
X760500Y489500D01*
G01X865000Y488500D02*
X861500D01*
X860500Y489500D01*
X774500D01*
G01X837319Y-438119D02*
Y-518119D01*
G01X874910Y360160D02*
X867820D01*
X855140Y347480D01*
X851950D01*
X850540Y346070D01*
G01X867914Y286803D02*
Y290355D01*
G01X863974Y294678D02*
Y298230D01*
G01D02*
Y301782D01*
G01X860422Y298230D02*
X863974D01*
G01D02*
X867526D01*
G01X867914Y290355D02*
Y293907D01*
G01X864362Y290355D02*
X867914D01*
G01D02*
X871466D01*
G01X863974Y304518D02*
Y308070D01*
G01D02*
Y311622D01*
G01X860422Y308070D02*
X863974D01*
G01D02*
X867526D01*
G01X867914Y312393D02*
Y315945D01*
G01D02*
Y319497D01*
G01X864362Y315945D02*
X867914D01*
G01D02*
X871466D01*
G01X871849Y304518D02*
Y308070D01*
G01D02*
Y311622D01*
G01X868297Y308070D02*
X871849D01*
G01D02*
X875401D01*
G01X874910Y360160D02*
Y367340D01*
X867800Y374450D01*
Y445300D01*
X870500Y448000D01*
G01X1034819Y-438119D02*
Y-518119D01*
G01X1066819Y-422119D02*
X1034819D01*
G01X1055500Y360000D02*
Y358000D01*
X1053000Y355500D01*
Y328500D01*
X1023500Y299000D01*
Y226500D01*
X1031524Y218476D01*
G01X1050819Y-438119D02*
Y-406119D01*
G01X1062819Y-422119D02*
G02I-12000J0D01*
G01X1057669D02*
G02I-6850J0D01*
G01X1084646Y39165D02*
Y43267D01*
G01D02*
Y47369D01*
G01X1080544Y43267D02*
X1084646D01*
G01D02*
X1088748D01*
G01X1111500Y718500D02*
X1083500D01*
X1079616Y722384D01*
X1073384D01*
G01X1110318Y275600D02*
X1110718D01*
X1110818Y275500D01*
X1146500D01*
G01X1126969Y727981D02*
X1124739Y725751D01*
X1118749D01*
X1117500Y727000D01*
Y742500D01*
X1115500Y744500D01*
Y753000D01*
X1110500Y758000D01*
Y759500D01*
X1107000Y763000D01*
G01X1129260Y714350D02*
X1128521Y715089D01*
Y715363D01*
X1127116Y716768D01*
X1123732D01*
X1114000Y726500D01*
Y739998D01*
X1106600Y747398D01*
Y753000D01*
G01X1189000Y421500D02*
Y426500D01*
X1195000Y432500D01*
X1209000D01*
X1212500Y436000D01*
G01D02*
Y438500D01*
X1213000Y439000D01*
Y448500D01*
X1217000Y452500D01*
G01X1246000Y263500D02*
X1253696D01*
X1271000Y280804D01*
Y337500D01*
X1277077Y343577D01*
Y389423D01*
X1257268Y409232D01*
Y468120D01*
X1284200Y495052D01*
Y522800D01*
X1313250Y551850D01*
Y577226D01*
X1329317Y593293D01*
Y601232D01*
X1299946Y630603D01*
X1293300Y637250D01*
Y648690D01*
X1294200Y649590D01*
Y711800D01*
X1289500Y716500D01*
G01X1257000Y33000D02*
X1264000Y40000D01*
X1303000D01*
X1306000Y43000D01*
G01X1258504Y329331D02*
Y368701D01*
G01X1291300Y540900D02*
Y539900D01*
X1279100Y527700D01*
Y495102D01*
X1253768Y469770D01*
Y373437D01*
X1258504Y368701D01*
G01X1258000Y555400D02*
Y593319D01*
X1273681Y609000D01*
X1274098D01*
X1282125Y617027D01*
Y640806D01*
X1285200Y643881D01*
Y646119D01*
X1283800Y647519D01*
Y660493D01*
X1285500Y662193D01*
Y708028D01*
X1287962Y710490D01*
G01X1250500Y567000D02*
X1254500Y571000D01*
Y594769D01*
X1272231Y612500D01*
X1272648D01*
X1276500Y616352D01*
Y636250D01*
X1278105Y637855D01*
Y668855D01*
X1279600Y670350D01*
Y694800D01*
G01X1311000Y350000D02*
X1284500Y376500D01*
Y461500D01*
X1288500Y465500D01*
Y475200D01*
X1297700Y484400D01*
Y525181D01*
X1319350Y546831D01*
Y574698D01*
X1335417Y590765D01*
Y605397D01*
X1319000Y621814D01*
Y695500D01*
X1318000Y696500D01*
G01X1292500Y730478D02*
Y728000D01*
X1302550Y717950D01*
Y672019D01*
X1307675Y666894D01*
Y627825D01*
X1310500Y625000D01*
G01X1333100Y58600D02*
X1327600D01*
X1312000Y43000D01*
X1306000D01*
G01X1302500Y559500D02*
X1307000Y564000D01*
Y573412D01*
G01X1338526Y29526D02*
Y33428D01*
G01X1334624Y29526D02*
X1338526D01*
G01X1362865Y60039D02*
X1367067D01*
G01X1362865Y96260D02*
X1367067D01*
G01Y55837D02*
Y60039D01*
G01D02*
Y64241D01*
G01Y60039D02*
X1371269D01*
G01X1367067Y92058D02*
Y96260D01*
G01D02*
Y100462D01*
G01Y96260D02*
X1371269D01*
G01X1392657Y55837D02*
Y60039D01*
G01D02*
Y64241D01*
G01X1388455Y60039D02*
X1392657D01*
G01Y92058D02*
Y96260D01*
G01D02*
Y100462D01*
G01X1388455Y96260D02*
X1392657D01*
X50000Y659500D03*
X109000Y844220D03*
X112900Y988500D03*
X128000Y544050D03*
X166200Y506500D03*
X182000Y577500D03*
X176938Y680465D03*
X182500Y677500D03*
X234000Y562000D03*
X253500Y707250D03*
X330250Y80000D03*
X339000Y878500D03*
X336000Y871500D03*
X339000Y894000D03*
Y885500D03*
X337300Y949500D03*
X353740Y133300D03*
X352040Y143000D03*
X349829Y153400D03*
X355084Y172441D03*
X351929Y162200D03*
X377757Y145670D03*
X371457Y155080D03*
X374582Y161404D03*
X367665Y363430D03*
X368055Y380500D03*
X368555Y385000D03*
Y376500D03*
Y389000D03*
X368165Y393402D03*
X370500Y518000D03*
X390355Y139371D03*
X380920Y139370D03*
X384056Y145670D03*
X390355D03*
X396655D03*
X387205Y167715D03*
X384041Y170888D03*
X384030Y177120D03*
X393504Y218109D03*
X389500Y319150D03*
X392589Y317729D03*
X394055Y335000D03*
X391325Y324520D03*
X386755Y326100D03*
X384160Y328812D03*
X391555Y338350D03*
X396055Y338000D03*
X395855Y366890D03*
X391628Y358852D03*
X394915Y359725D03*
X387265Y384370D03*
X394935Y385150D03*
X382803Y385207D03*
X391215Y384900D03*
X388500Y400575D03*
X390543Y391950D03*
X387000Y404275D03*
X388750Y951750D03*
X399783Y136237D03*
X406110Y145660D03*
X402954Y145670D03*
X400983Y334054D03*
X397983Y333998D03*
X400523Y325283D03*
X400055Y343146D03*
X397117Y364138D03*
X404920Y369487D03*
X412794Y361613D03*
X408925Y361680D03*
X400395Y362450D03*
X400885Y354120D03*
X412794Y369487D03*
X408857D03*
X399923Y372000D03*
X412794Y412796D03*
X408857D03*
X412794Y404922D03*
X408857Y420670D03*
X412794D03*
X404920D03*
X406555Y428300D03*
X428375Y119735D03*
X418940Y125000D03*
X428149Y161416D03*
X418727Y192902D03*
X420668Y337991D03*
X428542Y349802D03*
X424605Y337991D03*
X420668Y341928D03*
Y349802D03*
X416731Y337991D03*
X420668Y345865D03*
X416731Y341928D03*
Y369487D03*
X420668Y353739D03*
X416731Y365550D03*
X424605D03*
X416731Y361613D03*
X420668Y369487D03*
X428542Y357676D03*
X416731Y377363D03*
X428445Y373550D03*
X420668Y377363D03*
Y385237D03*
Y389174D03*
X416731Y393111D03*
Y397048D03*
X420668Y393111D03*
Y397048D03*
X416731Y400985D03*
X424605Y389174D03*
X416731Y412796D03*
X439540Y124500D03*
X443910Y174041D03*
X444290Y345865D03*
Y397048D03*
X440353D03*
X436416D03*
X456103D03*
X448227D03*
X471851Y349802D03*
X467914Y345865D03*
X471851Y361613D03*
Y369487D03*
Y353739D03*
Y357676D03*
Y377363D03*
Y381300D03*
X483955Y318600D03*
X559750Y264500D03*
X568500Y147500D03*
X599000Y804000D03*
X622500Y696500D03*
X625000Y706000D03*
X691400Y231100D03*
X710100Y182700D03*
X720500Y478750D03*
X723000Y996500D03*
X731498D03*
X739368Y996610D03*
X727558Y996500D03*
X756000Y180000D03*
X780000Y250000D03*
X862500Y65000D03*
X865000Y488500D03*
X874000Y56000D03*
X873500Y61500D03*
X884500Y323500D03*
X881000Y736500D03*
X935000Y51500D03*
X945000Y141500D03*
X947500Y153000D03*
X959900Y180700D03*
X974500Y188500D03*
X975007Y194300D03*
X1015000Y477500D03*
X1011500Y667500D03*
X1022000Y492500D03*
X1022500Y637500D03*
X1027504Y853366D03*
X1055500Y360000D03*
X1062940Y629945D03*
X1054080Y680630D03*
X1103300Y492000D03*
X1114500Y645000D03*
X1132500Y333000D03*
X1132440Y676555D03*
Y686004D03*
X1126157Y695435D03*
X1132440Y701714D03*
X1126093Y704874D03*
X1132406Y704904D03*
X1132440Y698564D03*
X1129260Y714350D03*
X1129277Y711210D03*
X1126969Y727981D03*
X1130900Y766700D03*
X1124460Y768140D03*
X1131095Y799965D03*
X1124796Y800150D03*
X1144425Y325500D03*
X1143000Y629000D03*
X1148150Y663956D03*
X1135589Y673368D03*
X1136150Y676500D03*
X1135685Y679613D03*
X1138708Y667113D03*
X1135589Y682854D03*
Y695415D03*
X1144880Y707720D03*
X1138320Y710066D03*
X1140710Y707750D03*
X1146370Y769310D03*
X1142095Y773774D03*
X1150310Y783840D03*
X1142120Y795830D03*
X1145270D03*
X1167098Y663932D03*
X1160748Y660807D03*
Y657657D03*
X1160768Y676535D03*
X1154470Y673363D03*
X1152090Y677010D03*
X1160741Y667099D03*
X1163914Y673352D03*
X1163944Y667076D03*
X1157670Y707960D03*
X1163968Y708000D03*
X1158100Y769700D03*
X1162450Y769190D03*
X1161051Y792660D03*
X1164196Y795814D03*
X1154800Y799000D03*
X1179662Y673421D03*
X1182815Y676573D03*
X1182785Y685977D03*
X1176520Y685970D03*
X1179663Y685959D03*
X1173365Y695397D03*
X1169800Y682200D03*
X1173392Y685974D03*
X1182815Y701696D03*
X1182796Y708013D03*
X1179703Y714331D03*
X1173347Y714350D03*
X1176503Y714342D03*
X1170950Y795960D03*
X1185965Y676573D03*
X1190000Y699500D03*
X1218040Y719850D03*
X1249773Y551500D03*
X1279600Y694800D03*
X1287962Y710490D03*
X1289500Y716500D03*
X1292500Y730478D03*
X1307000Y729100D03*
Y732500D03*
X1300491Y732991D03*
X1318000Y696500D03*
X1354900Y522600D03*
X1355900Y536600D03*
X1379600Y584200D03*
X1378800Y594900D03*
X1377800Y603800D03*
X1378082Y614266D03*
X1381637Y611225D03*
X1381578Y607117D03*
X1387200Y584100D03*
X1384400Y598300D03*
Y601900D03*
G54D23*
G01X1302000Y475000D02*
X1303600Y476600D01*
Y522300D01*
X1327400Y546100D01*
Y574969D01*
X1340917Y588486D01*
Y608083D01*
X1332000Y617000D01*
Y678356D01*
X1331268Y679088D01*
Y680912D01*
X1331950Y681594D01*
Y842268D01*
X1315668Y858550D01*
X1275486D01*
X1175661Y958375D01*
X1088186D01*
X1085211Y961350D01*
X1031386D01*
X992500Y922464D01*
Y772730D01*
X987924Y768154D01*
X922706D01*
X842000Y848860D01*
Y873500D01*
X789190Y926310D01*
Y969192D01*
X777382Y981000D01*
X490000D01*
X483650Y987350D01*
X421350D01*
X417000Y991700D01*
X393700D01*
X391900Y989900D01*
X386100D01*
X384307Y991693D01*
X307693D01*
X294500Y978500D01*
X120972D01*
X50004Y907532D01*
Y905808D01*
X31500Y887304D01*
Y874136D01*
X15064Y857700D01*
X8200D01*
G01X176938Y680465D02*
X178173D01*
X198207Y700499D01*
X250992D01*
X258993Y708500D01*
X637182D01*
X666382Y737700D01*
X859912D01*
X864962Y732650D01*
X998195D01*
X1027032Y761487D01*
Y852894D01*
X1027504Y853366D01*
G01X183000Y865750D02*
X200250D01*
X204000Y862000D01*
G01X247500Y829500D02*
Y829000D01*
X248500Y828000D01*
X255000D01*
X271000Y844000D01*
X398500D01*
X415000Y860500D01*
X495000D01*
X497000Y858500D01*
X662000D01*
X669000Y851500D01*
X713000D01*
X718500Y857000D01*
X814000D01*
X852500Y818500D01*
Y817000D01*
X917000Y752500D01*
G01X362500Y286000D02*
X339500D01*
X313429Y259929D01*
Y256464D01*
X311965Y255000D01*
X308500D01*
X274820Y221320D01*
Y169680D01*
X278500Y166000D01*
Y113903D01*
X293903Y98500D01*
X294500D01*
G01X343000Y89000D02*
X337500D01*
X336000Y90500D01*
X333000D01*
G01X884500Y323500D02*
X886700Y321300D01*
Y266171D01*
X868279Y247750D01*
X585345D01*
X565845Y267250D01*
X524550D01*
X504418Y247118D01*
X441918D01*
X438000Y243200D01*
X398871D01*
X393500Y237829D01*
Y235000D01*
X395429Y233071D01*
Y225500D01*
X393504Y223575D01*
Y218109D01*
G01X499390Y153500D02*
Y156390D01*
X504000Y161000D01*
Y181617D01*
X457000Y228617D01*
Y242500D01*
X456000Y243500D01*
G01X503500Y153500D02*
Y156500D01*
X506500Y159500D01*
Y182653D01*
X459500Y229653D01*
Y243000D01*
X460000Y243500D01*
G01X640500Y444500D02*
X655000D01*
X658200Y441300D01*
X661800D01*
X664425Y443925D01*
X750425D01*
X764500Y458000D01*
X779000D01*
G01X691400Y231100D02*
X691500Y231000D01*
X860400D01*
G01X783500Y649000D02*
X796000Y661500D01*
X908000D01*
X923700Y645800D01*
X975300D01*
X989000Y659500D01*
G01X876000Y435500D02*
X874800Y434300D01*
Y375700D01*
X879510Y370990D01*
Y355410D01*
G01X1030000Y403500D02*
X1035500Y398000D01*
Y339000D01*
X972457Y275957D01*
Y190543D01*
X974500Y188500D01*
G01X1032200Y921500D02*
X1088000D01*
X1099623Y909877D01*
Y869123D01*
G01X1299500Y236000D02*
X1331836Y268336D01*
Y305836D01*
X1364416Y338416D01*
Y356972D01*
X1299800Y421588D01*
Y477500D01*
X1300700Y478400D01*
Y523938D01*
X1322350Y545588D01*
Y573455D01*
X1338417Y589522D01*
Y606640D01*
X1325800Y619257D01*
Y701118D01*
X1329450Y704768D01*
Y841232D01*
X1314632Y856050D01*
X1274450D01*
X1181500Y949000D01*
G01X1250450Y462000D02*
Y443747D01*
X1248203Y441500D01*
X1247388D01*
X1246050Y440162D01*
Y438338D01*
X1247388Y437000D01*
X1248203D01*
X1250000Y435203D01*
Y422000D01*
G01X1247800Y472750D02*
Y469200D01*
X1250450Y466550D01*
Y462000D01*
G01X1263000Y278500D02*
Y284000D01*
X1265500Y286500D01*
Y316500D01*
X1250000Y332000D01*
Y422000D01*
G54D14*
X153937Y238898D03*
Y246772D03*
Y260551D03*
X224015Y234961D03*
Y246772D03*
Y260551D03*
G54D24*
G01X1138320Y710066D02*
Y711544D01*
X1136000Y713864D01*
Y720134D01*
X1131567Y724567D01*
X1130383D01*
X1126969Y727981D01*
G54D15*
X180118Y729409D03*
X200118Y739409D03*
X190118D03*
X210118D03*
X230118Y729409D03*
Y739409D03*
X220118D03*
X250118D03*
X240118D03*
X260118Y729409D03*
Y739409D03*
X270118Y729409D03*
Y739409D03*
G54D25*
G01X709750Y585200D02*
X709620D01*
X709520Y585300D01*
X701480D01*
X701380Y585200D01*
X441333D01*
X374133Y518000D01*
X370500D01*
G01X645500Y481000D02*
X596000D01*
X586100Y471100D01*
X388885D01*
G01X601000Y543000D02*
X688000D01*
X757000Y474000D01*
G01X626500Y557350D02*
X726083D01*
X726933Y558200D01*
X816396D01*
X816496Y558100D01*
X821900D01*
X823500Y556500D01*
G01X757000Y474000D02*
X757802D01*
G01X819000Y473000D02*
X819500Y473500D01*
X886000D01*
X888500Y476000D01*
X931500D01*
X943500Y488000D01*
G01X823500Y556500D02*
X898500D01*
X927102Y527898D01*
X1066102D01*
X1078000Y516000D01*
X1105000D01*
X1108750Y512250D01*
X1154250D01*
X1166250Y500250D01*
X1172050D01*
X1173100Y499200D01*
G01X963500Y536500D02*
X930500D01*
G01X1015000Y477500D02*
X1015500Y477000D01*
Y456675D01*
X1048400Y423775D01*
Y331172D01*
X992360Y275132D01*
Y188967D01*
X945000Y141607D01*
Y141500D01*
G01X963500Y488000D02*
X967000D01*
X971500Y483500D01*
X1009000D01*
X1012500Y487000D01*
X1014000D01*
G01X990500Y536500D02*
X963500D01*
G01X1008500Y533400D02*
X1008400Y533500D01*
X1006840D01*
X1003840Y536500D01*
X990500D01*
G01X1060000Y929500D02*
X1081500D01*
X1084000Y927000D01*
X1149000D01*
X1200000Y876000D01*
Y873000D01*
X1219000Y854000D01*
Y847000D01*
X1229000Y837000D01*
X1232660D01*
X1240660Y829000D01*
G01X1213000Y249500D02*
Y372196D01*
X1205000Y380196D01*
Y417468D01*
X1199968Y422500D01*
X1195000D01*
G01X1207000Y243500D02*
X1213000Y249500D01*
G01X1217000Y537000D02*
X1218200Y535800D01*
X1223104D01*
X1225750Y538446D01*
Y552485D01*
X1238373Y565108D01*
Y593677D01*
X1238500Y593804D01*
Y622500D01*
X1252500Y636500D01*
Y698500D01*
X1263000Y709000D01*
Y717000D01*
G54D16*
X402953Y23622D03*
X413189D03*
X423425D03*
G54D26*
G01X128000Y544050D02*
X125091Y546959D01*
Y547124D01*
X115844Y556371D01*
Y620344D01*
X157750Y662250D01*
G01X154625Y550290D02*
X174517D01*
X192577Y568350D01*
X281650D01*
X300210Y549790D01*
X315725D01*
G01D02*
X326290D01*
X327950Y551450D01*
X342463D01*
X347213Y546700D01*
G01X345500Y556500D02*
X322435D01*
X315725Y549790D01*
G01X351929Y332500D02*
X364055D01*
X381055Y315500D01*
X389366D01*
X390366Y314500D01*
X393880D01*
X394880Y315500D01*
X400165D01*
X400415Y315250D01*
X402695D01*
X402945Y315500D01*
X414802D01*
X416552Y313750D01*
X418748D01*
X418998Y314000D01*
X439845D01*
X443455Y317610D01*
X445395D01*
G54D17*
X585315Y44134D03*
X654527D03*
G54D27*
G01X299831Y144328D02*
X299857Y144355D01*
G03X300829Y146700I-2345J2346D01*
G01Y193169D01*
G02X301443Y194654I2100J1D01*
G01X337337Y230642D01*
X350097Y243402D01*
G03X351700Y247272I-3870J3870D01*
G01Y249947D01*
G02X354000Y255500I7852J1D01*
G01X395500Y297000D01*
G02X399363Y298600I3864J-3865D01*
G01X442100D01*
G03X453709Y303408I1J16417D01*
G01X454800Y304500D01*
X465376Y315075D01*
X466593Y316292D01*
G02X471200Y318200I4607J-4608D01*
G01X482989D01*
G03X483955Y318600I0J1366D01*
G01X303677Y144328D02*
G02X303327Y144473I0J495D01*
G01X302200Y145600D01*
G02X302129Y145771I171J171D01*
G01Y193170D01*
G02X302363Y193735I800J0D01*
G01X302364D01*
X329284Y220726D01*
X338257Y229723D01*
X351016Y242482D01*
G03X353000Y247272I-4789J4790D01*
G01Y249947D01*
G02X354919Y254580I6552J0D01*
G01X396419Y296080D01*
G02X399364Y297300I2945J-2945D01*
G01X442100D01*
Y297299D01*
G03X454629Y302488I1J17718D01*
G01X455720Y303580D01*
X465904Y313764D01*
X465905D01*
X467513Y315372D01*
G02X471201Y316900I3688J-3687D01*
G01X486023D01*
G03X486588Y317134I0J799D01*
G01X487377Y317921D01*
G03X487612Y318487I-564J566D01*
G01Y318606D01*
G01X305852Y163800D02*
X306785Y164734D01*
G03X307600Y166700I-1966J1967D01*
G01Y188161D01*
G02X308908Y191320I4469J0D01*
G01X313522Y195933D01*
X313639Y196050D01*
X313640D01*
X338227Y220637D01*
Y220638D01*
X398771Y281182D01*
X401744Y284154D01*
G02X414893Y289600I13148J-13147D01*
G01X448206D01*
G03X451885Y291125I-2J5205D01*
G01X471930Y311170D01*
G02X478283Y313800I6351J-6353D01*
G01X489961D01*
G03X490805Y314150I-1J1195D01*
G01X490855Y314200D01*
G03X491257Y315171I-971J971D01*
G01Y315952D01*
G01X309698Y163800D02*
G02X308900Y165727I1927J1927D01*
G01Y188160D01*
G02X309828Y190400I3168J0D01*
G01X314178Y194750D01*
X314179D01*
X339147Y219718D01*
G02X340091Y220032I778J-763D01*
G03X341035Y220347I165J1078D01*
G01X341883Y221196D01*
G03X342198Y222140I-762J779D01*
G02X342513Y223084I1077J165D01*
G01X343361Y223932D01*
G02X344305Y224247I779J-763D01*
G03X345249Y224561I166J1077D01*
G01X346098Y225410D01*
G03X346412Y226354I-763J778D01*
G02X346727Y227298I1078J165D01*
G01X347575Y228146D01*
G02X348519Y228461I779J-762D01*
G03X349463Y228776I165J1077D01*
G01X350312Y229624D01*
G03X350627Y230568I-763J779D01*
G02X350941Y231512I1077J166D01*
G01X357038Y237609D01*
G02X357982Y237923I778J-763D01*
G03X358926Y238238I165J1078D01*
G01X359774Y239087D01*
G03X360089Y240031I-762J779D01*
G02X360404Y240975I1077J165D01*
G01X361252Y241823D01*
G02X362196Y242138I779J-763D01*
G03X363140Y242452I166J1077D01*
G01X363989Y243301D01*
G03X364303Y244245I-763J778D01*
G02X364618Y245189I1078J165D01*
G01X365466Y246037D01*
G02X366410Y246352I779J-762D01*
G03X367354Y246667I165J1077D01*
G01X368203Y247515D01*
G03X368518Y248459I-763J779D01*
G02X368832Y249403I1077J166D01*
G01X376420Y256991D01*
G02X377364Y257305I778J-763D01*
G03X378308Y257620I165J1078D01*
G01X379156Y258469D01*
G03X379471Y259413I-762J779D01*
G02X379786Y260357I1077J165D01*
G01X380634Y261205D01*
G02X381578Y261520I779J-763D01*
G03X382522Y261834I166J1077D01*
G01X383371Y262683D01*
G03X383685Y263627I-763J778D01*
G02X384000Y264571I1078J165D01*
G01X384848Y265419D01*
G02X385792Y265734I779J-762D01*
G03X386736Y266049I165J1077D01*
G01X387585Y266897D01*
G03X387900Y267841I-763J779D01*
G02X388214Y268785I1077J166D01*
G01X392107Y272678D01*
G02X393050Y272992I778J-763D01*
G03X393994Y273307I165J1077D01*
G01X394843Y274155D01*
G03X395158Y275099I-763J779D01*
G02X395464Y276035I1077J166D01*
G02X395472Y276043I775J-767D01*
G01X396321Y276892D01*
G02X397265Y277207I779J-763D01*
G03X398209Y277521I166J1077D01*
G01X399057Y278370D01*
G03X399372Y279314I-762J779D01*
G02X399687Y280258I1077J165D01*
G01X402664Y283235D01*
G02X414892Y288300I12228J-12228D01*
G01X448205D01*
G03X452805Y290205I0J6506D01*
G01X472850Y310250D01*
G02X478282Y312500I5432J-5432D01*
G01X489960D01*
G03X491725Y313230I1J2496D01*
G01X493983Y315488D01*
G02X495103Y315952I1120J-1120D01*
G01X313402Y156000D02*
X314082Y156681D01*
G03X314629Y158000I-1319J1320D01*
G01Y184670D01*
G02X315243Y186155I2100J1D01*
G01X336308Y207220D01*
X336309D01*
X365158Y236069D01*
X365159D01*
X386444Y257354D01*
G02X388488Y258200I2042J-2042D01*
G01X390911D01*
G03X395947Y260286I0J7123D01*
G01X401581Y265920D01*
G02X404913Y267300I3333J-3334D01*
G01X410000D01*
G03X413348Y268688I-1J4735D01*
G01X420568Y275908D01*
G02X429000Y279400I8431J-8432D01*
G01X456499D01*
G03X458985Y280431I-1J3515D01*
G01X463527Y284971D01*
G02X470115Y287700I6588J-6588D01*
G01X491275D01*
G03X493735Y288719I0J3479D01*
G01X501135Y296119D01*
G03X501855Y297857I-1738J1738D01*
G01Y312100D01*
G03X501253Y313555I-2057J1D01*
G01X500607Y314200D01*
G01X512000Y320000D02*
X511630Y319631D01*
G03X510955Y318000I1631J-1630D01*
G01Y293799D01*
G02X508665Y288270I-7822J1D01*
G01X500924Y280530D01*
G02X497954Y279300I-2971J2972D01*
G01X475166D01*
G03X472824Y278330I0J-3312D01*
G01X466574Y272080D01*
G02X463964Y271000I-2608J2610D01*
G01X443995D01*
G03X443105Y270555I-11J-1090D01*
G02X442215Y270110I-879J645D01*
G01X441015D01*
G02X440125Y270555I-11J1090D01*
G03X439235Y271000I-879J-645D01*
G01X438035D01*
G03X437145Y270555I-11J-1090D01*
G02X436255Y270110I-879J645D01*
G01X435055D01*
G02X434165Y270555I-11J1090D01*
G03X433275Y271000I-879J-645D01*
G01X428191D01*
G03X427105Y270550I0J-1536D01*
G01X422341Y265786D01*
G03X422026Y264842I762J-779D01*
G02X421711Y263898I-1077J-165D01*
G01X420863Y263049D01*
G02X419919Y262734I-779J763D01*
G03X418975Y262420I-166J-1077D01*
G01X418126Y261571D01*
G03X417812Y260627I763J-778D01*
G02X417497Y259683I-1078J-165D01*
G01X416648Y258835D01*
G02X415704Y258520I-779J762D01*
G03X414760Y258205I-165J-1077D01*
G01X409027Y252472D01*
X409028D01*
X408959Y252403D01*
G02X404361Y250500I-4596J4598D01*
G01X396791D01*
G03X394464Y249536I0J-3291D01*
G01X388586Y243658D01*
G03X388271Y242714I763J-779D01*
G02X387957Y241770I-1077J-166D01*
G01X387108Y240921D01*
G02X386164Y240606I-779J763D01*
G03X385220Y240292I-166J-1077D01*
G01X384372Y239443D01*
G03X384057Y238499I762J-779D01*
G02X383742Y237555I-1077J-165D01*
G01X382894Y236707D01*
G02X381950Y236392I-779J762D01*
G03X381006Y236077I-165J-1077D01*
G01X380157Y235229D01*
G03X379843Y234285I763J-778D01*
G02X379528Y233341I-1078J-165D01*
G01X378680Y232492D01*
G02X377736Y232177I-779J763D01*
G03X376792Y231863I-166J-1077D01*
G01X369572Y224643D01*
G03X369257Y223699I762J-779D01*
G02X368943Y222755I-1077J-166D01*
G01X368094Y221907D01*
G02X367150Y221592I-779J762D01*
G03X366206Y221277I-165J-1077D01*
G01X365358Y220429D01*
G03X365043Y219485I762J-779D01*
G02X364728Y218541I-1077J-165D01*
G01X363880Y217692D01*
G02X362936Y217378I-778J763D01*
G03X361992Y217063I-165J-1078D01*
G01X361143Y216214D01*
G03X360829Y215270I763J-778D01*
G02X360514Y214326I-1078J-165D01*
G01X359665Y213478D01*
G02X358721Y213163I-779J762D01*
G03X357778Y212849I-165J-1077D01*
G01X353056Y208127D01*
G03X352742Y207183I763J-778D01*
G02X352427Y206239I-1078J-165D01*
G01X351578Y205391D01*
G02X350634Y205076I-779J762D01*
G03X349690Y204761I-165J-1077D01*
G01X348842Y203913D01*
G03X348527Y202969I763J-779D01*
G02X348213Y202025I-1077J-166D01*
G01X347364Y201176D01*
G02X346420Y200862I-778J763D01*
G03X345476Y200547I-165J-1078D01*
G01X339757Y194828D01*
G03X336929Y188000I6829J-6828D01*
G01Y182361D01*
G03X337374Y181471I1090J-11D01*
G02X337819Y180581I-645J-879D01*
G01Y179381D01*
G02X337374Y178491I-1090J-11D01*
G03X336929Y177601I645J-879D01*
G01Y176401D01*
G03X337374Y175511I1090J-11D01*
G02X337819Y174621I-645J-879D01*
G01Y173421D01*
G02X337374Y172531I-1090J-11D01*
G03X336929Y171641I645J-879D01*
G01Y165020D01*
G02X332729Y160820I-4200J0D01*
G01X331012D01*
G03X330122Y160375I-11J-1090D01*
G02X329232Y159930I-879J645D01*
G01X328032D01*
G02X327142Y160375I-11J1090D01*
G03X326252Y160820I-879J-645D01*
G01X325052D01*
G03X323748Y160280I0J-1844D01*
G01X323398Y159930D01*
G03X322729Y158315I1615J-1615D01*
G01Y153124D01*
G03X323029Y152400I1024J0D01*
G01X323151Y152278D01*
G03X325029Y151500I1878J1878D01*
G03X325122Y151505I-3J932D01*
G03X325688Y151773I-93J927D01*
G01X326422Y152507D01*
G01X508500Y320000D02*
X509057Y319442D01*
G02X509655Y318000I-1442J-1443D01*
G01Y293800D01*
G02X507745Y289190I-6521J1D01*
G01X500005Y281450D01*
G02X497953Y280600I-2052J2052D01*
G01X475166D01*
G03X471904Y279249I-1J-4612D01*
G01X465655Y273000D01*
G02X463965Y272300I-1690J1690D01*
G01X428190D01*
G03X426186Y271470I1J-2836D01*
G01X408039Y253323D01*
G02X404362Y251800I-3677J3677D01*
G01X396790D01*
G03X393545Y250456I1J-4591D01*
G01X393045Y249956D01*
X393044D01*
X387670Y244582D01*
G03X387646Y244559I1642J-1737D01*
G01X338837Y195748D01*
G03X335628Y188000I7749J-7748D01*
G01X335629D01*
Y165020D01*
G02X332729Y162120I-2900J0D01*
G01X325053D01*
G03X322828Y161199I-2J-3144D01*
G01X322478Y160849D01*
G03X321429Y158316I2535J-2534D01*
G01Y153123D01*
G03X322109Y151481I2324J1D01*
G01X322108D01*
X322231Y151358D01*
G03X325031Y150199I2798J2798D01*
G03X325254Y150211I-8J2233D01*
G01X325807Y150269D01*
G02X326000Y150200I24J-237D01*
G02X326422Y149181I-1019J-1019D01*
G01Y148944D01*
G01X317248Y156000D02*
X316411Y156838D01*
G02X315929Y158000I1162J1163D01*
G01Y164484D01*
G02X316374Y165374I1090J11D01*
G03X316819Y166264I-645J879D01*
G01Y167464D01*
G03X316374Y168354I-1090J11D01*
G02X315929Y169244I645J879D01*
G01Y170444D01*
G02X316374Y171334I1090J11D01*
G03X316819Y172224I-645J879D01*
G01Y173424D01*
G03X316374Y174314I-1090J11D01*
G02X315929Y175204I645J879D01*
G01Y176404D01*
G02X316374Y177294I1090J11D01*
G03X316819Y178184I-645J879D01*
G01Y179384D01*
G03X316374Y180274I-1090J11D01*
G02X315929Y181164I645J879D01*
G01Y184670D01*
G02X316163Y185235I799J0D01*
G01X322934Y192006D01*
X322935D01*
G02X323212Y192211I779J-763D01*
G02X323879Y192321I502J-968D01*
G03X324823Y192635I166J1077D01*
G01X325672Y193484D01*
G03X325986Y194428I-763J778D01*
G02X326301Y195372I1078J165D01*
G01X327150Y196221D01*
G02X328093Y196535I778J-763D01*
G03X329037Y196850I165J1077D01*
G01X329886Y197698D01*
G03X330201Y198642I-763J779D01*
G02X330515Y199586I1077J166D01*
G01X331364Y200435D01*
G02X332308Y200750I779J-763D01*
G03X333252Y201064I166J1077D01*
G01X334100Y201913D01*
G03X334415Y202857I-762J779D01*
G02X334730Y203801I1077J165D01*
G01X353229Y222300D01*
G02X354173Y222614I778J-763D01*
G03X355117Y222929I165J1078D01*
G01X355965Y223778D01*
G03X356280Y224722I-762J779D01*
G02X356595Y225666I1077J165D01*
G01X357443Y226514D01*
G02X358387Y226829I779J-763D01*
G03X359331Y227143I166J1077D01*
G01X360180Y227992D01*
G03X360494Y228936I-763J778D01*
G02X360809Y229880I1078J165D01*
G01X361657Y230728D01*
G02X362601Y231043I779J-762D01*
G03X363545Y231358I165J1077D01*
G01X364394Y232206D01*
G03X364709Y233150I-763J779D01*
G02X365023Y234094I1077J166D01*
G01X374338Y243409D01*
G02X375282Y243723I778J-763D01*
G03X376226Y244038I165J1078D01*
G01X377074Y244887D01*
G03X377389Y245831I-762J779D01*
G02X377704Y246775I1077J165D01*
G01X378552Y247623D01*
G02X379496Y247938I779J-763D01*
G03X380440Y248252I166J1077D01*
G01X381289Y249101D01*
G03X381603Y250045I-763J778D01*
G02X381918Y250989I1078J165D01*
G01X382766Y251837D01*
G02X383710Y252152I779J-762D01*
G03X384654Y252467I165J1077D01*
G01X385503Y253315D01*
G03X385818Y254259I-763J779D01*
G02X386129Y255200I1077J166D01*
G02X386132Y255203I772J-769D01*
G01X387364Y256435D01*
G02X388487Y256900I1123J-1123D01*
G01X390911D01*
G03X396867Y259367I0J8423D01*
G01X402500Y265000D01*
G02X404914Y266000I2414J-2414D01*
G01X410000D01*
G03X414268Y267768I0J6036D01*
G01X421488Y274988D01*
G02X428999Y278100I7513J-7512D01*
G01X456500D01*
G03X459905Y279511I-1J4816D01*
G01X464447Y284051D01*
G02X470116Y286400I5670J-5667D01*
G01X491276D01*
G03X494654Y287799I-1J4779D01*
G01X502055Y295200D01*
G03X503155Y297856I-2658J2657D01*
G01Y299629D01*
G02X503600Y300519I1090J11D01*
G03X504045Y301409I-645J879D01*
G01Y302609D01*
G03X503600Y303499I-1090J11D01*
G02X503155Y304389I645J879D01*
G01Y312100D01*
G02X503722Y313469I1936J0D01*
G01X504453Y314200D01*
G01X1131000Y665200D02*
X1131302Y665502D01*
X1133061D01*
X1133998Y666439D01*
Y667765D01*
X1133995Y667768D01*
Y670888D01*
X1135589Y672482D01*
Y673368D01*
G01X1160741Y667099D02*
Y666212D01*
X1162346Y664607D01*
Y663283D01*
X1162348Y663281D01*
Y656923D01*
G54D18*
X702559Y290355D03*
X714369Y308070D03*
X820669Y315945D03*
X832479Y298230D03*
X856104Y308070D03*
X852164Y315945D03*
X871849Y298230D03*
X867914Y290355D03*
X863974Y298230D03*
X871849Y308070D03*
X867914Y315945D03*
X863974Y308070D03*
G54D28*
G01X174000Y830500D02*
X172742D01*
X148742Y854500D01*
X52383D01*
X34150Y872733D01*
Y886074D01*
X44576Y896500D01*
X44842D01*
X54854Y906512D01*
Y908028D01*
X118826Y972000D01*
X293500D01*
X310943Y989443D01*
X380557D01*
X385789Y984211D01*
X389711D01*
X394950Y989450D01*
X415000D01*
X420450Y984000D01*
X482500D01*
X487750Y978750D01*
X776450D01*
X785500Y969700D01*
G01X1093500Y905500D02*
Y902638D01*
X1091518Y900656D01*
Y896160D01*
X1092370Y895308D01*
Y864360D01*
X1090768Y862758D01*
Y859686D01*
X1039582Y808500D01*
X1034120D01*
X1029928Y804308D01*
Y761201D01*
X999127Y730400D01*
X834722D01*
X831622Y733500D01*
X668500D01*
X639000Y704000D01*
X260500D01*
X252500Y696000D01*
X204000D01*
X183500Y675500D01*
X156000D01*
X138562Y658062D01*
X51438D01*
X50000Y659500D01*
G01X170500Y835500D02*
X149500Y856500D01*
X54000D01*
X49000Y861500D01*
G01X989000Y757150D02*
X987150Y759000D01*
X921747D01*
X829500Y851247D01*
Y866873D01*
X814923Y881450D01*
X516050D01*
X508220Y889280D01*
X432163D01*
X427000Y884117D01*
Y883165D01*
X395235Y851400D01*
X268647D01*
X261797Y844550D01*
X166950D01*
X152300Y859200D01*
X55274D01*
X37232Y877242D01*
G01X757000Y896400D02*
X436030D01*
X409301Y869671D01*
Y868719D01*
X394282Y853700D01*
X267694D01*
X263244Y849250D01*
X190521D01*
X187261Y852510D01*
X163990D01*
X155000Y861500D01*
X56266D01*
X41054Y876712D01*
Y881378D01*
X37758Y884674D01*
G01X40304Y887220D02*
X63724Y863800D01*
X179958D01*
X192208Y851550D01*
X249500D01*
X251500Y853550D01*
X264050D01*
X266500Y856000D01*
X393329D01*
X423000Y885671D01*
Y886623D01*
X435327Y898950D01*
X800676D01*
X831800Y867826D01*
Y852200D01*
X920696Y763304D01*
X989934D01*
X997350Y770720D01*
Y920454D01*
X1033396Y956500D01*
X1083200D01*
G01X835000Y719000D02*
Y720500D01*
X823500Y732000D01*
X669500D01*
X640000Y702500D01*
X261500D01*
X253500Y694500D01*
X205000D01*
X184500Y674000D01*
X157500D01*
X139000Y655500D01*
X52000D01*
G01X62704Y739620D02*
X63204D01*
X75584Y752000D01*
X544500D01*
X595000Y802500D01*
X597500D01*
X599000Y804000D01*
G01X1077000Y943075D02*
X1037229D01*
X1014332Y920178D01*
Y900515D01*
X1015150Y899697D01*
Y765563D01*
X993087Y743500D01*
X912071D01*
X847071Y808500D01*
X725000D01*
X723050Y810450D01*
X720950D01*
X719334Y808834D01*
X716166D01*
X715700Y809300D01*
X674300D01*
X671750Y806750D01*
X595750D01*
X542700Y753700D01*
X74879D01*
X74179Y753000D01*
X73584D01*
X66804Y746220D01*
X55304D01*
G01X82804Y794920D02*
X85354Y792370D01*
X567748D01*
X589612Y814234D01*
X845968D01*
X913502Y746700D01*
X991760D01*
X1011950Y766890D01*
Y888670D01*
X1008516Y892104D01*
Y894964D01*
X1010500Y896948D01*
Y920873D01*
X1036152Y946525D01*
X1078430D01*
X1081455Y943500D01*
X1165880D01*
X1296689Y812691D01*
Y739411D01*
X1307000Y729100D01*
G01X85204Y798220D02*
X89554Y793870D01*
X567126D01*
X594490Y821234D01*
X841090D01*
X914124Y748200D01*
X991138D01*
X1010450Y767512D01*
Y888048D01*
X1005582Y892916D01*
Y918077D01*
X1035530Y948025D01*
X1079052D01*
X1082077Y945000D01*
X1166502D01*
X1298190Y813312D01*
Y812070D01*
X1298189Y812069D01*
Y741311D01*
X1307000Y732500D01*
G01X388500Y955250D02*
X336750D01*
X334000Y958000D01*
X290000D01*
X282500Y950500D01*
X113084D01*
X105804Y943220D01*
G01X429500Y311000D02*
X429000Y311500D01*
X372000D01*
X354000Y329500D01*
X350686D01*
X347879Y332307D01*
Y337379D01*
X342758Y342500D01*
X303800D01*
X284850Y361450D01*
X188950D01*
X168000Y340500D01*
X148000D01*
X131500Y324000D01*
G01X122906Y331953D02*
X120924Y333935D01*
Y372924D01*
X201750Y453750D01*
Y471140D01*
X216500Y485890D01*
Y516000D01*
G01X1241984Y796000D02*
X1207634Y830350D01*
X1144850D01*
X1144000Y829500D01*
X1076852D01*
X1032928Y785576D01*
Y759957D01*
X988521Y715550D01*
X825730D01*
X812330Y728950D01*
X775450D01*
X770500Y724000D01*
X671500D01*
X642000Y694500D01*
X261000D01*
X255500Y689000D01*
X207000D01*
X175000Y657000D01*
X163876D01*
X124000Y617124D01*
Y584708D01*
X123100Y583808D01*
Y556400D01*
X132500Y547000D01*
G01X1238047Y791953D02*
X1205750Y824250D01*
X1173750D01*
X1173150Y823650D01*
X1131850D01*
X1131120Y824380D01*
X1128880D01*
X1125894Y821394D01*
X1087606D01*
X1087600Y821400D01*
X1075118D01*
X1037428Y783710D01*
Y758091D01*
X989337Y710000D01*
X883758D01*
X881808Y708050D01*
X880192D01*
X878242Y710000D01*
X854758D01*
X853308Y708550D01*
X847808D01*
X847308Y708050D01*
X845692D01*
X843742Y710000D01*
X823428D01*
X811928Y721500D01*
X774744D01*
X772744Y719500D01*
X674500D01*
X645000Y690000D01*
X264000D01*
X258500Y684500D01*
X210000D01*
X178000Y652500D01*
X165742D01*
X131550Y618308D01*
Y560550D01*
X132500Y559600D01*
G01X1240045Y788957D02*
Y792713D01*
X1207008Y825750D01*
X1172750D01*
X1172150Y825150D01*
X1132850D01*
X1131550Y826450D01*
X1078046D01*
X1035928Y784332D01*
Y758713D01*
X989765Y712550D01*
X823000D01*
X809600Y725950D01*
X777072D01*
X772122Y721000D01*
X673500D01*
X644000Y691500D01*
X263000D01*
X257500Y686000D01*
X209000D01*
X177000Y654000D01*
X165120D01*
X130050Y618930D01*
Y558450D01*
X132500Y556000D01*
G01X1243953Y789000D02*
Y790927D01*
X1206030Y828850D01*
X1145472D01*
X1144622Y828000D01*
X1077474D01*
X1034428Y784954D01*
Y759335D01*
X989143Y714050D01*
X825108D01*
X811708Y727450D01*
X776450D01*
X771500Y722500D01*
X672500D01*
X643000Y693000D01*
X262000D01*
X256500Y687500D01*
X208000D01*
X176000Y655500D01*
X164498D01*
X128550Y619552D01*
Y555450D01*
X132500Y551500D01*
G01X276500Y888500D02*
X271500D01*
X271000Y888000D01*
X226000D01*
X213000Y875000D01*
X132500D01*
X128000Y870500D01*
G01X187300Y457300D02*
X185500Y455500D01*
X151500D01*
X141232Y465768D01*
Y557232D01*
X145950Y561950D01*
Y605216D01*
X212784Y672050D01*
X274050D01*
X284000Y682000D01*
X645747D01*
X677547Y713800D01*
X775800D01*
X777550Y715550D01*
X809450D01*
X822450Y702550D01*
X970300D01*
X970750Y703000D01*
G01X975000Y701000D02*
X974250Y700250D01*
X821497D01*
X808497Y713250D01*
X779375D01*
X777625Y711500D01*
X678500D01*
X646500Y679500D01*
X391000D01*
X381250Y669750D01*
X213737D01*
X150998Y607011D01*
Y559498D01*
X144500Y553000D01*
Y467500D01*
X153500Y458500D01*
X183800D01*
X184900Y459600D01*
X188254D01*
X190554Y457300D01*
X191800D01*
G01X223500Y825500D02*
X220500Y822500D01*
X183158D01*
X165658Y805000D01*
X147084D01*
X146304Y804220D01*
G01X228000Y825000D02*
X225550Y827450D01*
X185279D01*
X166049Y808220D01*
X146500D01*
G01X141054Y795820D02*
X566954D01*
X593868Y822734D01*
X841712D01*
X914746Y749700D01*
X990516D01*
X1008950Y768134D01*
Y865403D01*
X1005000Y869353D01*
Y891376D01*
X1004082Y892294D01*
Y918699D01*
X1034909Y949526D01*
X1036151D01*
X1036152Y949525D01*
X1079674D01*
X1082699Y946500D01*
X1167124D01*
X1300750Y812874D01*
Y740872D01*
X1307272Y734350D01*
X1307767D01*
X1313500Y728617D01*
Y710000D01*
G01X198500Y563000D02*
X175121Y539621D01*
Y536499D01*
X169000Y530378D01*
Y519500D01*
X164350Y514850D01*
Y488650D01*
X171500Y481500D01*
Y478699D01*
G01X153050Y486500D02*
X154000Y487450D01*
Y517500D01*
X173621Y537121D01*
Y540879D01*
X197692Y564950D01*
X202550D01*
X203000Y564500D01*
G01X1022500Y637500D02*
X1021450Y636450D01*
X902758D01*
X893758Y645450D01*
X863037D01*
X862887Y645300D01*
X804534D01*
X798883Y639649D01*
X763359D01*
X757508Y645500D01*
X675671D01*
X649739Y671432D01*
X391136D01*
X383654Y663950D01*
X375950D01*
X339950Y627950D01*
Y615899D01*
X320101Y596050D01*
X317050D01*
X315500Y594500D01*
X170242D01*
X163305Y587563D01*
Y554750D01*
G01X162500Y670000D02*
X164500Y672000D01*
X185000D01*
X205500Y692500D01*
X254000D01*
X262000Y700500D01*
X640500D01*
X669450Y729450D01*
X766550D01*
X768000Y728000D01*
G01X1300491Y732991D02*
Y733009D01*
X1293500Y740000D01*
Y813758D01*
X1165258Y942000D01*
X1080833D01*
X1077808Y945025D01*
X1036774D01*
X1012500Y920751D01*
Y896826D01*
X1010016Y894342D01*
Y892726D01*
X1013450Y889292D01*
Y766268D01*
X992382Y745200D01*
X912880D01*
X845346Y812734D01*
X590234D01*
X568370Y790870D01*
X150683D01*
X150225Y790412D01*
G01X232000Y825000D02*
X225200Y831800D01*
X214371D01*
X214221Y831950D01*
X186950D01*
X165500Y810500D01*
X152900D01*
X150900Y812500D01*
G01X215250Y833750D02*
X214000Y835000D01*
X187000D01*
X164500Y812500D01*
X154500D01*
G01X157500Y867500D02*
X162000Y872000D01*
X216900D01*
X217450Y872550D01*
X315379D01*
X328329Y885500D01*
X331829D01*
G01X755000Y727500D02*
X754500Y727000D01*
X669500D01*
X641000Y698500D01*
X262500D01*
X254500Y690500D01*
X206000D01*
X185500Y670000D01*
X173500D01*
X166000Y662500D01*
G01X166500Y650500D02*
X178500D01*
X205000Y677000D01*
X265500D01*
X274500Y686000D01*
X646000D01*
X676300Y716300D01*
X774071D01*
X776071Y718300D01*
X810601D01*
X822401Y706500D01*
X842715D01*
X844365Y704850D01*
X848635D01*
X849135Y705350D01*
X854635D01*
X855785Y706500D01*
X877215D01*
X878865Y704850D01*
X883135D01*
X884785Y706500D01*
X992657D01*
X1024387Y738230D01*
G01X335500Y868000D02*
X329550D01*
X322050Y860500D01*
X263500D01*
X256000Y868000D01*
X172000D01*
G01X336000Y871500D02*
X326500D01*
X317500Y862500D01*
X264329D01*
X256829Y870000D01*
X170400D01*
X168400Y868000D01*
G01X182500Y677500D02*
X203000Y698000D01*
X252000D01*
X260000Y706000D01*
X625000D01*
G01X229055Y497000D02*
X231015Y495040D01*
Y446536D01*
X313551Y364000D01*
X324818D01*
X333404Y355414D01*
X335044D01*
X345456Y345002D01*
X348010D01*
X355512Y337500D01*
X386816D01*
X392666Y331650D01*
X398579D01*
X400983Y334054D01*
G01X228319Y524798D02*
X227105Y523584D01*
Y448324D01*
X313429Y362000D01*
X324696D01*
X332782Y353914D01*
X334422D01*
X344834Y343502D01*
X346998D01*
X354500Y336000D01*
X373017D01*
X382055Y326962D01*
X384927D01*
X385915Y327950D01*
X387522D01*
X388322Y327150D01*
X396405D01*
X398272Y325283D01*
X400523D01*
G01X234000Y562000D02*
X233005Y561005D01*
Y528716D01*
X232235Y527946D01*
Y523530D01*
X231755Y523050D01*
Y512500D01*
X230255Y511000D01*
Y503760D01*
X232515Y501500D01*
Y458424D01*
X281850Y409089D01*
Y397823D01*
X313259Y366414D01*
X324526D01*
X334026Y356914D01*
X335666D01*
X346078Y346502D01*
X348632D01*
X356134Y339000D01*
X387438D01*
X393288Y333150D01*
X394822D01*
X395670Y333998D01*
X397983D01*
G01X215250Y833750D02*
X215300Y833800D01*
X249700D01*
X249950Y833550D01*
X254050D01*
X269600Y849100D01*
X396600D01*
X417500Y870000D01*
X500449D01*
X506399Y864050D01*
X663450D01*
X668450Y859050D01*
X680050D01*
X690450Y869450D01*
X714808D01*
X716708Y867550D01*
X741858D01*
X743758Y869450D01*
X808044D01*
X922294Y755200D01*
X989808D01*
X1002950Y768342D01*
Y865550D01*
X1000082Y868418D01*
Y920357D01*
X1033251Y953526D01*
X1086175D01*
X1086176Y953525D01*
X1169804D01*
X1274829Y848500D01*
X1310000D01*
X1312000Y850500D01*
G01X391555Y338350D02*
X389405Y340500D01*
X356756D01*
X349254Y348002D01*
X346700D01*
X336288Y358414D01*
X334648D01*
X325148Y367914D01*
X313881D01*
X295450Y386345D01*
Y388765D01*
X299305Y392620D01*
Y393757D01*
X295437Y397625D01*
X294731D01*
X291134Y394027D01*
X290428D01*
X289719Y394736D01*
Y395442D01*
X293316Y399040D01*
Y399746D01*
X292607Y400455D01*
X291901D01*
X288304Y396857D01*
X287598D01*
X286889Y397566D01*
Y398272D01*
X290486Y401870D01*
Y402576D01*
X289777Y403285D01*
X289071D01*
X285474Y399687D01*
X284768D01*
X284059Y400396D01*
Y401102D01*
X287656Y404700D01*
Y405406D01*
X234015Y459046D01*
Y503040D01*
X231755Y505300D01*
Y510200D01*
X233255Y511700D01*
Y520576D01*
X234055Y521376D01*
Y526688D01*
X234185Y526818D01*
Y527138D01*
G01X424605Y365550D02*
X422318Y363263D01*
Y360929D01*
X421352Y359963D01*
X420621D01*
X418205Y357547D01*
Y356816D01*
X417239Y355850D01*
X416508D01*
X414444Y353786D01*
Y353055D01*
X413378Y351989D01*
X410856D01*
X409956Y351089D01*
X403282D01*
X399839Y347646D01*
X397721D01*
X395905Y345830D01*
Y344905D01*
X393550Y342550D01*
X356828D01*
X349876Y349502D01*
X347322D01*
X336910Y359914D01*
X335270D01*
X322934Y372250D01*
X318600D01*
X318100Y372750D01*
Y374656D01*
X317600Y375156D01*
X316600D01*
X316100Y374656D01*
Y372750D01*
X315600Y372250D01*
X312160D01*
X301747Y382663D01*
Y383371D01*
X306425Y388049D01*
Y388759D01*
X304799Y390385D01*
X304093D01*
X299165Y385458D01*
X298459D01*
X297750Y386167D01*
Y386873D01*
X302678Y391800D01*
Y392506D01*
X294188Y400996D01*
X235515Y459668D01*
Y508940D01*
X234755Y509700D01*
G01X237055Y513500D02*
Y512864D01*
X237053Y512862D01*
Y461497D01*
X237052Y461496D01*
Y460254D01*
X310385Y386921D01*
Y386213D01*
X305706Y381534D01*
Y380826D01*
X306413Y380119D01*
X307121D01*
X311800Y384798D01*
X312508D01*
X313215Y384091D01*
Y383383D01*
X308536Y378704D01*
Y377996D01*
X309243Y377289D01*
X309951D01*
X314630Y381968D01*
X315338D01*
X316045Y381261D01*
Y380553D01*
X311366Y375874D01*
Y375166D01*
X312073Y374459D01*
X312781D01*
X317460Y379138D01*
X318168D01*
X335892Y361414D01*
X337532D01*
X347944Y351002D01*
X350498D01*
X357450Y344050D01*
X392928D01*
X394911Y346033D01*
Y346251D01*
X397306Y348646D01*
X398739D01*
X402182Y352089D01*
X409541D01*
X410507Y353055D01*
Y353786D01*
X412747Y356026D01*
X413478D01*
X414444Y356992D01*
Y359326D01*
X416731Y361613D01*
G01X242003Y506327D02*
Y491896D01*
X241805Y491698D01*
Y487840D01*
X242305Y487340D01*
X245205D01*
X245705Y486840D01*
Y485840D01*
X245205Y485340D01*
X242305D01*
X241805Y484840D01*
Y483840D01*
X242305Y483340D01*
X245205D01*
X245705Y482840D01*
Y481840D01*
X245205Y481340D01*
X242305D01*
X241805Y480840D01*
Y479840D01*
X242305Y479340D01*
X245205D01*
X245705Y478840D01*
Y477840D01*
X245205Y477340D01*
X242305D01*
X241805Y476840D01*
Y475840D01*
X242305Y475340D01*
X245205D01*
X245705Y474840D01*
Y473840D01*
X245205Y473340D01*
X242305D01*
X241805Y472840D01*
Y471840D01*
X242305Y471340D01*
X245205D01*
X245705Y470840D01*
Y469840D01*
X245205Y469340D01*
X242305D01*
X241805Y468840D01*
Y467840D01*
X242305Y467340D01*
X245205D01*
X245704Y466841D01*
Y465839D01*
X245205Y465340D01*
X242305D01*
X241805Y464840D01*
Y461867D01*
X242868Y460804D01*
X243574D01*
X246397Y463628D01*
X247103D01*
X247812Y462919D01*
Y462213D01*
X244989Y459389D01*
Y458683D01*
X245698Y457974D01*
X246404D01*
X249227Y460798D01*
X249933D01*
X250642Y460089D01*
Y459383D01*
X247819Y456559D01*
Y455371D01*
X349188Y354002D01*
X394585D01*
X394602Y354019D01*
X394609D01*
X395309Y354719D01*
X395845D01*
X396723Y355597D01*
Y355682D01*
X397811Y356770D01*
X400765D01*
X403805Y359810D01*
X409905D01*
X411708Y361613D01*
X412794D01*
G01X245205Y504679D02*
X244663Y504137D01*
Y494862D01*
X247205Y492320D01*
Y465648D01*
X253562Y459291D01*
Y458583D01*
X250741Y455762D01*
Y455054D01*
X251448Y454347D01*
X252156D01*
X254977Y457168D01*
X255685D01*
X256392Y456461D01*
Y455753D01*
X253571Y452932D01*
Y452224D01*
X254278Y451517D01*
X254986D01*
X257807Y454338D01*
X258515D01*
X259222Y453631D01*
Y452923D01*
X256401Y450102D01*
Y449394D01*
X257108Y448687D01*
X257816D01*
X260637Y451508D01*
X261345D01*
X262052Y450801D01*
Y450093D01*
X259231Y447272D01*
Y446564D01*
X259938Y445857D01*
X260646D01*
X263467Y448678D01*
X264175D01*
X264882Y447971D01*
Y447263D01*
X262061Y444442D01*
Y443734D01*
X262768Y443027D01*
X263476D01*
X266297Y445848D01*
X267005D01*
X267712Y445141D01*
Y444433D01*
X264891Y441612D01*
Y440904D01*
X265598Y440197D01*
X266306D01*
X269127Y443018D01*
X269835D01*
X270542Y442311D01*
Y441603D01*
X267721Y438782D01*
Y438074D01*
X268428Y437367D01*
X269136D01*
X271957Y440188D01*
X272665D01*
X273694Y439159D01*
Y438359D01*
X271215Y435880D01*
Y434579D01*
X271685Y434110D01*
Y433627D01*
X349810Y355502D01*
X393263D01*
X393980Y356219D01*
X395845D01*
X397396Y357770D01*
X399985D01*
X403895Y361680D01*
X408925D01*
G01X239555Y519500D02*
X239005Y518950D01*
Y512692D01*
X238553Y512240D01*
Y460875D01*
X336514Y362914D01*
X338154D01*
X348566Y352502D01*
X355945D01*
X357957Y350490D01*
Y346050D01*
X358457Y345550D01*
X359457D01*
X359957Y346050D01*
Y350490D01*
X360457Y350990D01*
X361457D01*
X361957Y350490D01*
Y346050D01*
X362457Y345550D01*
X363457D01*
X363957Y346050D01*
Y350490D01*
X364457Y350990D01*
X365457D01*
X365957Y350490D01*
Y346050D01*
X366457Y345550D01*
X367457D01*
X367957Y346050D01*
Y350490D01*
X368457Y350990D01*
X373505D01*
X374005Y350490D01*
Y346050D01*
X374505Y345550D01*
X375505D01*
X376005Y346050D01*
Y350490D01*
X376505Y350990D01*
X377505D01*
X378005Y350490D01*
Y346050D01*
X378505Y345550D01*
X379505D01*
X380005Y346050D01*
Y350490D01*
X380505Y350990D01*
X381505D01*
X382005Y350490D01*
Y346050D01*
X382505Y345550D01*
X383505D01*
X384005Y346050D01*
Y350490D01*
X384505Y350990D01*
X387825D01*
X388380Y350434D01*
Y348560D01*
X389463Y347477D01*
X390997D01*
X392170Y348650D01*
X394522D01*
X395605Y349733D01*
Y350180D01*
X397845Y352420D01*
X399185D01*
X400885Y354120D01*
G01X400395Y362450D02*
X395664Y357719D01*
X393112D01*
X392395Y357002D01*
X350432D01*
X296782Y410652D01*
Y411845D01*
X299602Y414665D01*
Y415373D01*
X298895Y416080D01*
X298187D01*
X295367Y413260D01*
X294659D01*
X293952Y413967D01*
Y414675D01*
X296772Y417495D01*
Y418203D01*
X296065Y418910D01*
X295357D01*
X292537Y416090D01*
X291829D01*
X291122Y416797D01*
Y417505D01*
X293942Y420325D01*
Y421033D01*
X293235Y421740D01*
X292527D01*
X289707Y418920D01*
X288999D01*
X288292Y419627D01*
Y420335D01*
X291112Y423155D01*
Y423863D01*
X290405Y424570D01*
X289697D01*
X286877Y421750D01*
X286169D01*
X285462Y422457D01*
Y423165D01*
X288282Y425985D01*
Y426693D01*
X287575Y427400D01*
X286867D01*
X284047Y424580D01*
X283339D01*
X282632Y425287D01*
Y425995D01*
X285452Y428815D01*
Y429523D01*
X284745Y430230D01*
X284037D01*
X281217Y427410D01*
X280509D01*
X279802Y428117D01*
Y428825D01*
X282622Y431645D01*
Y432353D01*
X281915Y433060D01*
X281207D01*
X278387Y430240D01*
X277679D01*
X276972Y430947D01*
Y431655D01*
X279792Y434475D01*
Y435183D01*
X279085Y435890D01*
X278377D01*
X275557Y433070D01*
X274849D01*
X274142Y433777D01*
Y434485D01*
X276962Y437305D01*
Y438013D01*
X248705Y466270D01*
Y492942D01*
X246613Y495034D01*
Y501365D01*
G01X232000Y825000D02*
X239500D01*
X245950Y831450D01*
X254950D01*
X270000Y846500D01*
X397500D01*
X413050Y862050D01*
X429687D01*
X429887Y861850D01*
X431669D01*
X431869Y862050D01*
X662621D01*
X667621Y857050D01*
X701792D01*
X709942Y865200D01*
X803042D01*
X804442Y863800D01*
X810865D01*
X921465Y753200D01*
X990637D01*
X1004950Y767513D01*
Y866550D01*
X1002082Y869418D01*
Y919528D01*
X1034080Y951526D01*
X1082474D01*
X1083000Y951000D01*
X1169500D01*
X1275000Y845500D01*
X1305000D01*
X1312500Y838000D01*
G01X256055Y531016D02*
Y526078D01*
X257105Y525028D01*
Y524070D01*
X257129Y524046D01*
Y521392D01*
X256705Y520968D01*
Y497674D01*
X257705Y496674D01*
Y470690D01*
X317655Y410740D01*
Y402511D01*
X350356Y369810D01*
X371001D01*
X371813Y368998D01*
X376926D01*
X377426Y368498D01*
Y367150D01*
X377926Y366650D01*
X378926D01*
X379426Y367150D01*
Y368498D01*
X379926Y368998D01*
X380926D01*
X381426Y368498D01*
Y367150D01*
X381926Y366650D01*
X382926D01*
X383426Y367150D01*
Y368498D01*
X383926Y368998D01*
X393747D01*
X395855Y366890D01*
G01X253679Y523137D02*
Y496456D01*
X254705Y495430D01*
Y469446D01*
X314655Y409496D01*
Y401267D01*
X349112Y366810D01*
X369757D01*
X370617Y365950D01*
X372863D01*
X375163Y363650D01*
X389123D01*
X389175Y363702D01*
X396681D01*
X397117Y364138D01*
G01X248855Y532300D02*
X248205Y531650D01*
Y511708D01*
X248105Y511608D01*
Y509992D01*
X248205Y509892D01*
Y506688D01*
X248655Y506238D01*
Y495114D01*
X250205Y493564D01*
Y467580D01*
X303098Y414687D01*
Y413979D01*
X299934Y410815D01*
Y410107D01*
X300641Y409400D01*
X301349D01*
X304513Y412564D01*
X305221D01*
X305928Y411857D01*
Y411149D01*
X302764Y407985D01*
Y407277D01*
X303471Y406570D01*
X304179D01*
X307343Y409734D01*
X308051D01*
X310155Y407630D01*
Y406130D01*
X309655Y405630D01*
X307495D01*
X306995Y405130D01*
Y404130D01*
X307495Y403630D01*
X309655D01*
X310155Y403130D01*
Y402371D01*
X310154Y402370D01*
Y399402D01*
X350704Y358852D01*
X352686D01*
X353186Y359352D01*
Y361794D01*
X353686Y362294D01*
X354686D01*
X355186Y361794D01*
Y359352D01*
X355686Y358852D01*
X356686D01*
X357186Y359352D01*
Y361794D01*
X357686Y362294D01*
X358686D01*
X359186Y361794D01*
Y359352D01*
X359686Y358852D01*
X360686D01*
X361186Y359352D01*
Y361794D01*
X361686Y362294D01*
X362686D01*
X363186Y361794D01*
Y359352D01*
X363686Y358852D01*
X391628D01*
G01X367665Y363430D02*
X365801Y365294D01*
X348506D01*
X313155Y400645D01*
Y408874D01*
X253205Y468824D01*
Y494808D01*
X252005Y496008D01*
Y511608D01*
X251729Y511884D01*
Y530294D01*
X252305Y530870D01*
Y533989D01*
X252055Y534239D01*
Y548760D01*
G01X420668Y369487D02*
X420482D01*
X418295Y367300D01*
X408132D01*
X407669Y366837D01*
X399803D01*
X396141Y370499D01*
X373986D01*
X373175Y371310D01*
X370913D01*
X370413Y371810D01*
Y373080D01*
X369913Y373580D01*
X368913D01*
X368413Y373080D01*
Y371810D01*
X367913Y371310D01*
X350978D01*
X319155Y403133D01*
Y411362D01*
X259205Y471312D01*
Y497296D01*
X259055Y497446D01*
Y500500D01*
G01X394915Y359725D02*
X394090Y360550D01*
X392547D01*
X392395Y360702D01*
X390861D01*
X390709Y360550D01*
X367765D01*
X364521Y363794D01*
X347884D01*
X311655Y400023D01*
Y408252D01*
X251705Y468202D01*
Y494186D01*
X250155Y495736D01*
Y506860D01*
X250055Y506960D01*
Y510800D01*
G01X260555Y525500D02*
Y522797D01*
X263738Y519614D01*
Y513159D01*
X262705Y512126D01*
Y509250D01*
X268035Y503920D01*
Y484175D01*
X267535Y483675D01*
X264535D01*
X264035Y483175D01*
Y474763D01*
X264535Y474263D01*
X265535D01*
X266035Y474763D01*
Y481175D01*
X266535Y481675D01*
X267535D01*
X268035Y481175D01*
Y473348D01*
X268535Y472848D01*
X269535D01*
X270035Y473348D01*
Y490230D01*
X270535Y490730D01*
X271535D01*
X272035Y490230D01*
Y471348D01*
X271535Y470848D01*
X268535D01*
X268035Y470348D01*
Y468848D01*
X323656Y413227D01*
Y404998D01*
X350104Y378550D01*
X363488D01*
X367288Y382350D01*
X368825D01*
X376175Y375000D01*
X396555D01*
X399555Y372000D01*
X399923D01*
G01X260605Y519245D02*
Y517917D01*
X262238Y516284D01*
Y513781D01*
X261205Y512748D01*
Y507898D01*
X261705Y507398D01*
X262435D01*
X262935Y506898D01*
Y505898D01*
X262435Y505398D01*
X261705D01*
X261205Y504898D01*
Y503230D01*
X262505Y501930D01*
Y488563D01*
X263005Y488063D01*
X264005D01*
X264505Y488563D01*
Y501430D01*
X265005Y501930D01*
X266005D01*
X266505Y501430D01*
Y486563D01*
X266005Y486063D01*
X263005D01*
X262505Y485563D01*
Y472256D01*
X322155Y412606D01*
Y411332D01*
X322156Y411331D01*
Y404376D01*
X349122Y377410D01*
X352203Y374330D01*
X361885D01*
X368055Y380500D01*
G01X260288Y514589D02*
Y514513D01*
X259705Y513930D01*
Y502608D01*
X261005Y501308D01*
Y471634D01*
X320655Y411984D01*
Y410710D01*
X320656Y410709D01*
Y403754D01*
X351600Y372810D01*
X364865D01*
X368555Y376500D01*
G01X428445Y373550D02*
X417050D01*
X416810Y373310D01*
X405480D01*
X399279Y379511D01*
X381638D01*
X373631Y387518D01*
Y388691D01*
X371202Y391120D01*
X367915D01*
X367483Y391552D01*
X367398D01*
X366698Y392252D01*
X364565D01*
X364065Y391752D01*
Y389070D01*
X363565Y388570D01*
X362565D01*
X362065Y389070D01*
Y391752D01*
X361565Y392252D01*
X360565D01*
X360065Y391752D01*
Y389070D01*
X359565Y388570D01*
X358565D01*
X358065Y389070D01*
Y391752D01*
X357565Y392252D01*
X356065D01*
X355863Y392050D01*
X354247D01*
X354045Y392252D01*
X350047D01*
X349547Y391752D01*
Y389070D01*
X349047Y388570D01*
X348047D01*
X347547Y389070D01*
Y391752D01*
X347047Y392252D01*
X344643D01*
X343795Y393100D01*
Y394600D01*
X344295Y395100D01*
X346115D01*
X346615Y395600D01*
Y396600D01*
X346115Y397100D01*
X344295D01*
X343795Y397600D01*
Y398600D01*
X344295Y399100D01*
X346115D01*
X346615Y399600D01*
Y400600D01*
X346115Y401100D01*
X344295D01*
X343795Y401600D01*
Y414026D01*
X337041Y420780D01*
X322548D01*
X277285Y466044D01*
Y505472D01*
X269605Y513152D01*
Y513153D01*
X268405Y514354D01*
Y522394D01*
X265505Y525294D01*
Y529411D01*
X263555Y531361D01*
Y534500D01*
G01X368555Y389000D02*
X366625Y387070D01*
X346425D01*
X342295Y391200D01*
Y413404D01*
X336419Y419280D01*
X321926D01*
X275785Y465422D01*
Y504850D01*
X268105Y512530D01*
Y512531D01*
X266905Y513731D01*
Y520691D01*
X264005Y523591D01*
Y526930D01*
X261255Y529680D01*
Y549000D01*
G01X368555Y385000D02*
X367816D01*
X365556Y382740D01*
X348519D01*
X340671Y390588D01*
Y412906D01*
X335797Y417780D01*
X321304D01*
X274245Y464840D01*
Y492507D01*
X273745Y493007D01*
X270745D01*
X270245Y493507D01*
Y503832D01*
X265939Y508138D01*
Y508846D01*
X267449Y510356D01*
Y511064D01*
X265405Y513108D01*
Y520069D01*
X262505Y522969D01*
Y526308D01*
X259555Y529258D01*
Y544161D01*
X257555Y546161D01*
Y549000D01*
G01X366600Y285800D02*
X362050Y281250D01*
Y277939D01*
X354611Y270500D01*
X331500D01*
X318179Y257179D01*
Y252067D01*
X316862Y250750D01*
X314996D01*
X313996Y251750D01*
X312750D01*
X278070Y217070D01*
Y172930D01*
X282000Y169000D01*
Y115000D01*
X298000Y99000D01*
X321000D01*
X335750Y84250D01*
X337500D01*
G01X368165Y393402D02*
X367755D01*
X367405Y393752D01*
X358061D01*
X355863Y395950D01*
X353387D01*
X345295Y404042D01*
Y414648D01*
X337663Y422280D01*
X323170D01*
X280029Y465422D01*
X278785Y466666D01*
Y506094D01*
X271105Y513774D01*
Y513775D01*
X270668Y514213D01*
X269905Y514976D01*
Y523016D01*
X268005Y524916D01*
Y532533D01*
X265455Y535083D01*
Y544853D01*
G01X269555Y536000D02*
X270605Y534950D01*
Y530692D01*
X270604Y530691D01*
Y529449D01*
X270605Y529448D01*
Y524438D01*
X271405Y523638D01*
Y515598D01*
X272167Y514836D01*
X272604Y514398D01*
X280285Y506716D01*
Y472190D01*
X282738Y469737D01*
Y469029D01*
X280996Y467287D01*
Y466579D01*
X281703Y465872D01*
X282411D01*
X284153Y467614D01*
X284861D01*
X285568Y466907D01*
Y466199D01*
X283826Y464457D01*
Y463749D01*
X284533Y463042D01*
X285241D01*
X286983Y464784D01*
X287691D01*
X288398Y464077D01*
Y463369D01*
X286656Y461627D01*
Y460919D01*
X287363Y460212D01*
X288071D01*
X289813Y461954D01*
X290521D01*
X291228Y461247D01*
Y460539D01*
X289486Y458797D01*
Y458089D01*
X290193Y457382D01*
X290901D01*
X292643Y459124D01*
X293351D01*
X294058Y458417D01*
Y457709D01*
X292316Y455967D01*
Y455259D01*
X293023Y454552D01*
X293731D01*
X295473Y456294D01*
X296181D01*
X296888Y455587D01*
Y454879D01*
X295146Y453137D01*
Y452429D01*
X295853Y451722D01*
X296561D01*
X298303Y453464D01*
X299011D01*
X306533Y445942D01*
Y445234D01*
X304791Y443492D01*
Y442784D01*
X305498Y442077D01*
X306206D01*
X307948Y443819D01*
X308656D01*
X309590Y442885D01*
Y442125D01*
X307969Y440504D01*
Y439604D01*
X311288Y436285D01*
X311290D01*
X323795Y423780D01*
X338285D01*
X346795Y415270D01*
Y407140D01*
X358683Y395252D01*
X371314D01*
X376631Y389935D01*
Y388762D01*
X382882Y382511D01*
X399489D01*
X406287Y375713D01*
X415081D01*
X416731Y377363D01*
G01X272571Y541150D02*
X273605Y540116D01*
Y530692D01*
X274405Y529892D01*
Y526030D01*
X277015Y523420D01*
Y514233D01*
X280434Y510813D01*
X281575Y509671D01*
X283286Y507959D01*
Y505473D01*
X283285Y505472D01*
Y473930D01*
X316868Y440347D01*
Y439639D01*
X314879Y437650D01*
Y436942D01*
X315586Y436235D01*
X316294D01*
X318283Y438224D01*
X318991D01*
X319698Y437517D01*
Y436809D01*
X317709Y434820D01*
Y434112D01*
X318416Y433405D01*
X319124D01*
X321113Y435394D01*
X321821D01*
X322528Y434687D01*
Y433979D01*
X320539Y431990D01*
Y431282D01*
X321246Y430575D01*
X321954D01*
X323943Y432564D01*
X324651D01*
X325358Y431857D01*
Y431149D01*
X323369Y429160D01*
Y428452D01*
X324076Y427745D01*
X324784D01*
X326773Y429734D01*
X327481D01*
X330435Y426780D01*
X339529D01*
X349795Y416514D01*
Y408384D01*
X350858Y407321D01*
X351566D01*
X354922Y410677D01*
X355630D01*
X356337Y409970D01*
Y409262D01*
X352981Y405906D01*
Y405198D01*
X353688Y404491D01*
X354396D01*
X357752Y407847D01*
X358460D01*
X359167Y407140D01*
Y406432D01*
X355811Y403076D01*
Y402368D01*
X356518Y401661D01*
X357226D01*
X360582Y405017D01*
X361290D01*
X361997Y404310D01*
Y403602D01*
X358641Y400246D01*
Y399538D01*
X359927Y398252D01*
X372558D01*
X386440Y384370D01*
X387265D01*
G01X271451Y544616D02*
Y543396D01*
X270621Y542566D01*
Y539529D01*
X272105Y538045D01*
Y530070D01*
X272905Y529270D01*
Y516221D01*
X273214Y515912D01*
X273666Y515459D01*
X281786Y507337D01*
Y506095D01*
X281785Y506094D01*
Y472970D01*
X311070Y443685D01*
Y443527D01*
X311090Y443507D01*
Y441503D01*
X311070Y441483D01*
Y438625D01*
X311910Y437785D01*
X311912D01*
X324417Y425280D01*
X338907D01*
X348295Y415892D01*
Y407762D01*
X359305Y396752D01*
X371936D01*
X378132Y390556D01*
Y389878D01*
X382803Y385207D01*
G01X394935Y385150D02*
X393335Y386750D01*
X390591D01*
X389935Y387409D01*
X376092Y401252D01*
X369299D01*
X352795Y417756D01*
Y417758D01*
X340773Y429780D01*
X332037D01*
X305335Y456482D01*
Y458458D01*
X307738Y460861D01*
Y462813D01*
X295035Y475516D01*
Y499028D01*
X290065Y503998D01*
Y512457D01*
X290565Y512957D01*
X298005D01*
X298505Y513457D01*
Y514457D01*
X298005Y514957D01*
X290565D01*
X290065Y515457D01*
Y516457D01*
X290565Y516957D01*
X298005D01*
X298505Y517457D01*
Y518457D01*
X298005Y518957D01*
X290565D01*
X290065Y519457D01*
Y520457D01*
X290565Y520957D01*
X298005D01*
X298505Y521457D01*
Y522457D01*
X298005Y522957D01*
X290565D01*
X290065Y523457D01*
Y523772D01*
X286875Y526962D01*
Y527670D01*
X289951Y530746D01*
Y531454D01*
X289244Y532161D01*
X288536D01*
X285460Y529085D01*
X284752D01*
X284045Y529792D01*
Y530500D01*
X287121Y533576D01*
Y534284D01*
X286414Y534991D01*
X285706D01*
X282630Y531915D01*
X281922D01*
X278937Y534900D01*
X278607D01*
X278367Y535140D01*
G01X270000Y870000D02*
X271500Y868500D01*
X317842D01*
X324842Y875500D01*
X339158D01*
X346158Y868500D01*
X346329D01*
X348329Y866500D01*
X371000D01*
G01X376041Y866041D02*
X374500Y864500D01*
X347329D01*
X338329Y873500D01*
X325671D01*
X316671Y864500D01*
X271000D01*
X270000Y865500D01*
G01X332129Y889371D02*
X329371D01*
X327242Y891500D01*
X279500D01*
X276500Y888500D01*
G01X280500Y955000D02*
Y957500D01*
X285500Y962500D01*
X293829D01*
X302853Y971524D01*
X363614D01*
G01X278050Y958500D02*
X278500D01*
X284500Y964500D01*
X293000D01*
X302500Y974000D01*
X361000D01*
G01X391215Y384900D02*
X390965Y385150D01*
X390922D01*
X390822Y385250D01*
X389967D01*
X388916Y386305D01*
X384545Y390676D01*
X383839D01*
X383403Y390240D01*
X382695D01*
X381988Y390947D01*
Y391655D01*
X382424Y392091D01*
Y392797D01*
X381715Y393506D01*
X381009D01*
X380573Y393070D01*
X379865D01*
X379158Y393777D01*
Y394485D01*
X379594Y394921D01*
Y395627D01*
X378885Y396336D01*
X378179D01*
X377743Y395900D01*
X377035D01*
X376328Y396607D01*
Y397315D01*
X376764Y397751D01*
Y398457D01*
X375470Y399752D01*
X368677D01*
X351295Y417134D01*
Y417136D01*
X340151Y428280D01*
X331415D01*
X302579Y457116D01*
Y457824D01*
X306238Y461483D01*
Y462191D01*
X305531Y462898D01*
X304823D01*
X301164Y459239D01*
X300456D01*
X299749Y459946D01*
Y460654D01*
X303408Y464313D01*
Y465021D01*
X302701Y465728D01*
X301993D01*
X298334Y462069D01*
X297626D01*
X296919Y462776D01*
Y463484D01*
X300578Y467143D01*
Y467851D01*
X299871Y468558D01*
X299163D01*
X295504Y464899D01*
X294796D01*
X294089Y465606D01*
Y466314D01*
X297748Y469973D01*
Y470681D01*
X297041Y471388D01*
X296333D01*
X292674Y467729D01*
X291966D01*
X291259Y468436D01*
Y469144D01*
X294918Y472803D01*
Y473511D01*
X294211Y474218D01*
X293503D01*
X289844Y470559D01*
X289136D01*
X284785Y474910D01*
Y476410D01*
X285285Y476910D01*
X287744D01*
X288244Y476410D01*
Y474573D01*
X288744Y474073D01*
X289744D01*
X290244Y474573D01*
Y476410D01*
X290744Y476910D01*
X293035D01*
X293535Y477410D01*
Y478410D01*
X293035Y478910D01*
X285285D01*
X284785Y479410D01*
Y480410D01*
X285285Y480910D01*
X293035D01*
X293535Y481410D01*
Y482410D01*
X293035Y482910D01*
X285285D01*
X284785Y483410D01*
Y484410D01*
X285285Y484910D01*
X293035D01*
X293535Y485410D01*
Y486410D01*
X293035Y486910D01*
X285285D01*
X284785Y487410D01*
Y488410D01*
X285285Y488910D01*
X293035D01*
X293535Y489410D01*
Y490410D01*
X293035Y490910D01*
X285285D01*
X284785Y491410D01*
Y492410D01*
X285285Y492910D01*
X293035D01*
X293535Y493410D01*
Y494410D01*
X293035Y494910D01*
X285285D01*
X284785Y495410D01*
Y497070D01*
X286495Y498780D01*
X292525D01*
G01X420668Y353739D02*
X422729Y355800D01*
X429000D01*
X430192Y356992D01*
Y370171D01*
X430095Y370268D01*
Y374234D01*
X429129Y375200D01*
X427761D01*
X427111Y374550D01*
X425450D01*
X422318Y377682D01*
Y378047D01*
X421352Y379013D01*
X404402D01*
X398140Y385275D01*
X397478D01*
X394503Y388250D01*
X391215D01*
X390780Y388687D01*
X376715Y402752D01*
X369923D01*
X336092Y436583D01*
X335384D01*
X331725Y432924D01*
X331017D01*
X330310Y433631D01*
Y434339D01*
X333969Y437998D01*
Y438706D01*
X333262Y439413D01*
X332554D01*
X328895Y435754D01*
X328187D01*
X327480Y436461D01*
Y437169D01*
X331139Y440828D01*
Y441536D01*
X330432Y442243D01*
X329724D01*
X326065Y438584D01*
X325357D01*
X324650Y439291D01*
Y439999D01*
X328309Y443658D01*
Y444366D01*
X327602Y445073D01*
X326894D01*
X323235Y441414D01*
X322527D01*
X321820Y442121D01*
Y442829D01*
X325479Y446488D01*
Y447196D01*
X324772Y447903D01*
X324064D01*
X320405Y444244D01*
X319697D01*
X318990Y444951D01*
Y445659D01*
X322649Y449318D01*
Y450026D01*
X321942Y450733D01*
X321234D01*
X317575Y447074D01*
X316867D01*
X316160Y447781D01*
Y448489D01*
X319819Y452148D01*
Y452856D01*
X319112Y453563D01*
X318404D01*
X314745Y449904D01*
X314037D01*
X313330Y450611D01*
Y451319D01*
X316989Y454978D01*
Y455686D01*
X316282Y456393D01*
X315574D01*
X311915Y452734D01*
X311207D01*
X310500Y453441D01*
Y454149D01*
X314159Y457808D01*
Y458516D01*
X313452Y459223D01*
X312744D01*
X309085Y455564D01*
X308377D01*
X307670Y456271D01*
Y456979D01*
X311329Y460638D01*
Y461346D01*
X296712Y475963D01*
Y502008D01*
X293823Y504897D01*
X292045D01*
G01X622500Y608500D02*
X574000D01*
X570500Y612000D01*
X433500D01*
X372500Y551000D01*
X364000D01*
X362000Y549000D01*
Y547654D01*
X350500Y536154D01*
Y533987D01*
X347363Y530850D01*
X343288D01*
X338205Y525767D01*
Y524563D01*
X323175Y509533D01*
X319571D01*
X308005Y497967D01*
Y496933D01*
X306554Y495482D01*
Y473999D01*
X305055Y472500D01*
G01X663500Y610500D02*
X660000Y614000D01*
X432500D01*
X371500Y553000D01*
X363000D01*
X359000Y549000D01*
Y547500D01*
X347950Y536450D01*
X340247D01*
X339105Y535308D01*
Y533692D01*
X340246Y532551D01*
Y530746D01*
X336005Y526505D01*
Y525192D01*
X322813Y512000D01*
X317838D01*
X304305Y498467D01*
Y477750D01*
X302555Y476000D01*
G01X957500Y585500D02*
X831500D01*
X824150Y592850D01*
X667850D01*
X664900Y595800D01*
X505897D01*
X505797Y595700D01*
X434354D01*
X377253Y538599D01*
X374162D01*
X360053Y524490D01*
X359490D01*
X358500Y523500D01*
X354313D01*
X329846Y499033D01*
X319471D01*
X311705Y491267D01*
Y474199D01*
X326405Y459499D01*
X332554D01*
X345045Y447008D01*
Y442610D01*
X367605Y420050D01*
Y416692D01*
X370275Y414022D01*
Y413540D01*
G01X369555Y417500D02*
Y426182D01*
X334738Y460999D01*
X327027D01*
X313205Y474821D01*
Y485761D01*
X324484Y497040D01*
X333953D01*
X350205Y513292D01*
Y515633D01*
X356572Y522000D01*
X359122D01*
X360112Y522990D01*
X360675D01*
X374784Y537099D01*
X377875D01*
X433276Y592500D01*
X626290D01*
X627716Y593926D01*
X629332D01*
X630758Y592500D01*
X666078D01*
X667228Y591350D01*
X823150D01*
X830950Y583550D01*
X959550D01*
X961500Y585500D01*
G01X384046Y536546D02*
X379444D01*
X378497Y535599D01*
X375406D01*
X360306Y520499D01*
X357193D01*
X351705Y515011D01*
Y512670D01*
X334575Y495540D01*
X325106D01*
X314705Y485139D01*
Y475443D01*
X327649Y462499D01*
X335360D01*
X377055Y420804D01*
Y407281D01*
X388836Y395500D01*
X396260D01*
X404236Y387524D01*
X417556D01*
X419206Y389174D01*
X420668D01*
G01X379000Y531000D02*
X375122D01*
X361620Y517498D01*
X360378D01*
X360377Y517499D01*
X358437D01*
X354705Y513767D01*
Y511426D01*
X335819Y492540D01*
X326350D01*
X317705Y483895D01*
Y476687D01*
X328893Y465499D01*
X336604D01*
X384500Y417603D01*
Y404158D01*
X386233Y402425D01*
X392575D01*
X393328Y401672D01*
X397383D01*
X400055Y399000D01*
X414055D01*
X416007Y397048D01*
X416731D01*
G01X381500Y534000D02*
X381401Y534099D01*
X376099D01*
X360999Y518999D01*
X357815D01*
X353205Y514389D01*
Y512048D01*
X335197Y494040D01*
X325728D01*
X316205Y484517D01*
Y476065D01*
X328271Y463999D01*
X335982D01*
X380555Y419426D01*
Y405903D01*
X389308Y397150D01*
X396489D01*
X399640Y394000D01*
X402179Y391461D01*
X417556D01*
X419206Y393111D01*
X420668D01*
G01X325873Y477006D02*
X323854Y479025D01*
Y481435D01*
X328959Y486540D01*
X348875D01*
X362335Y500000D01*
X364740D01*
X442740Y578000D01*
X619242D01*
X622692Y574550D01*
X624308D01*
X627758Y578000D01*
X642994D01*
X646444Y574550D01*
X648060D01*
X651510Y578000D01*
X667171D01*
X670171Y575000D01*
X703000D01*
X704350Y573650D01*
X706821D01*
X706904Y573733D01*
X727496D01*
X732729Y568500D01*
X733500D01*
G01X325873Y477006D02*
X327474Y475405D01*
X344454D01*
X345625Y474234D01*
Y474153D01*
X348118Y471660D01*
X348226D01*
X373436Y446450D01*
X375863D01*
X377005Y445308D01*
Y442594D01*
X386951Y432647D01*
X396898Y422700D01*
X405365D01*
X407395Y420670D01*
X408857D01*
G01X729900Y568500D02*
X726667Y571733D01*
X708362D01*
X708279Y571650D01*
X699350D01*
X698000Y573000D01*
X669342D01*
X666342Y576000D01*
X652339D01*
X648889Y572550D01*
X645615D01*
X642165Y576000D01*
X628587D01*
X625137Y572550D01*
X621863D01*
X618413Y576000D01*
X443569D01*
X361569Y494000D01*
X359226D01*
X350226Y485000D01*
X350164D01*
X349704Y484540D01*
X329788D01*
X325854Y480606D01*
G01X416731Y412796D02*
Y414258D01*
X414981Y416008D01*
Y420817D01*
X413378Y422420D01*
X407060D01*
X405280Y424200D01*
X398226D01*
X397224Y425202D01*
Y425203D01*
X389444Y432983D01*
X380663Y441765D01*
X379005Y443423D01*
Y446137D01*
X376692Y448450D01*
X374265D01*
X349054Y473661D01*
X348946D01*
X347625Y474982D01*
Y475089D01*
X347063Y475650D01*
X346884Y475829D01*
X345711Y477000D01*
X345560Y477150D01*
X345305Y477405D01*
X328850D01*
X325855Y480400D01*
Y480605D01*
X325854Y480606D01*
G01X404920Y420670D02*
X396099D01*
X343364Y473405D01*
X326645D01*
X321854Y478196D01*
Y482264D01*
X328130Y488540D01*
X345217D01*
X358730Y502053D01*
X363964D01*
X441911Y580000D01*
X661000D01*
X662000Y581000D01*
X702484D01*
X703034Y581550D01*
X707966D01*
X708066Y581450D01*
X740500D01*
X741500Y582450D01*
G01X737000Y583640D02*
X731360D01*
X725950Y589050D01*
X439808D01*
X373758Y523000D01*
X370196D01*
X337736Y490540D01*
X327301D01*
X319854Y483093D01*
Y477367D01*
X325816Y471405D01*
X342535D01*
X401144Y412796D01*
X408857D01*
G01X329695Y534650D02*
X333795Y538750D01*
X346443D01*
X355500Y547807D01*
Y548753D01*
X362247Y555500D01*
X370747D01*
X431547Y616300D01*
X692111D01*
X696161Y612250D01*
X832750D01*
X833500Y613000D01*
G01X321500Y688000D02*
X645500D01*
X675500Y718000D01*
X773366D01*
X775366Y720000D01*
X811306D01*
X822806Y708500D01*
X843120D01*
X845070Y706550D01*
X847930D01*
X848430Y707050D01*
X853930D01*
X855380Y708500D01*
X877620D01*
X879570Y706550D01*
X882430D01*
X884380Y708500D01*
X989959D01*
X1038928Y757469D01*
Y783088D01*
X1075740Y819900D01*
X1086978D01*
X1086984Y819894D01*
X1126516D01*
X1129122Y822500D01*
X1130878D01*
X1131228Y822150D01*
X1136700D01*
X1137500Y821350D01*
X1174350D01*
X1175750Y822750D01*
X1187008D01*
X1233000Y776758D01*
Y765500D01*
X1244950Y753550D01*
Y733708D01*
X1244371Y733129D01*
G01X338985Y467405D02*
X340321D01*
X400517Y407209D01*
X409541D01*
X411000Y408668D01*
Y410000D01*
X412000Y411000D01*
X413332D01*
X414444Y412112D01*
Y413480D01*
X412941Y414983D01*
X412210D01*
X411144Y416049D01*
Y417558D01*
X412794Y419208D01*
Y420670D01*
G01X330555Y467500D02*
X332460Y469405D01*
X341150D01*
X399409Y411146D01*
X410609D01*
X412259Y412796D01*
X412794D01*
G01X339888Y586388D02*
X366587D01*
X366697Y586498D01*
X366878D01*
X417380Y637000D01*
X417381D01*
X417832Y637450D01*
X606828D01*
X610378Y641000D01*
X674513D01*
X675014Y640499D01*
X676248D01*
X679048Y637699D01*
X680952D01*
X681253Y638000D01*
X752696D01*
X763196Y627500D01*
X893600D01*
X902100Y619000D01*
X963500D01*
X965250Y620750D01*
X1053250D01*
X1053500Y620500D01*
G01X1236500Y737925D02*
X1237450Y738875D01*
Y753180D01*
X1170780Y819850D01*
X1137350D01*
X1135550Y818050D01*
X1080941D01*
X1040428Y777537D01*
Y751513D01*
X986415Y697500D01*
X885668D01*
X881718Y693550D01*
X867330D01*
X866930Y693950D01*
X817123D01*
X800123Y710950D01*
X780328D01*
X775378Y706000D01*
X694380D01*
X692430Y707950D01*
X680570D01*
X647998Y675378D01*
X390131D01*
X382203Y667450D01*
X374328D01*
X361706Y654828D01*
X348226D01*
X346402Y653004D01*
G01X335500Y868000D02*
X338000D01*
X346000Y860000D01*
X394500D01*
X419000Y884500D01*
Y889000D01*
X433500Y903500D01*
X487000D01*
X488000Y904500D01*
G01X336000Y871500D02*
X337500D01*
X346879Y862121D01*
X393621D01*
X417000Y885500D01*
Y890000D01*
X432500Y905500D01*
X481500D01*
X483500Y907500D01*
G01X337300Y949500D02*
X339800Y952000D01*
X388500D01*
X388750Y951750D01*
G01X403255Y425950D02*
X394205Y435000D01*
X393355D01*
X363855Y464500D01*
X362378D01*
X360065Y466813D01*
Y481413D01*
X439652Y561000D01*
X622016D01*
X624116Y563100D01*
X708216D01*
X710849Y565733D01*
X719167D01*
X720700Y564200D01*
G01X717036Y563783D02*
X714353Y561100D01*
X624945D01*
X622845Y559000D01*
X440481D01*
X362065Y480584D01*
Y467642D01*
X363207Y466500D01*
X364755D01*
X385955Y445300D01*
X386955D01*
X403955Y428300D01*
X406555D01*
G01X1285557Y585000D02*
Y580057D01*
X1265500Y560000D01*
Y548642D01*
X1261258Y544400D01*
X1258813D01*
X1245282Y530869D01*
Y529474D01*
X1234107Y518299D01*
X1200020D01*
X1198021Y516300D01*
X1171384D01*
X1151684Y536000D01*
X1127513D01*
X1087013Y576500D01*
X807758D01*
X807008Y577250D01*
X790596D01*
X788208Y579638D01*
X757396D01*
X744258Y566500D01*
X729071D01*
X725838Y569733D01*
X709191D01*
X706558Y567100D01*
X622458D01*
X620358Y565000D01*
X437994D01*
X364994Y492000D01*
X362072D01*
X349575Y479503D01*
G01X349815Y475550D02*
X349886Y475621D01*
X351444D01*
X438823Y563000D01*
X621187D01*
X623287Y565100D01*
X707387D01*
X710020Y567733D01*
X725009D01*
X728242Y564500D01*
X756050D01*
X769188Y577638D01*
X787379D01*
X789767Y575250D01*
X802433D01*
X803183Y574500D01*
X1082000D01*
X1123000Y533500D01*
X1149829D01*
X1169029Y514300D01*
X1198850D01*
X1200849Y516299D01*
X1234936D01*
X1247282Y528645D01*
Y530040D01*
X1259642Y542400D01*
X1262087D01*
X1267500Y547813D01*
Y559171D01*
X1291432Y583103D01*
Y595568D01*
X1289570Y597430D01*
G01X559500Y604500D02*
X556200Y607800D01*
X505922D01*
X501522Y603400D01*
X430400D01*
X374500Y547500D01*
X366500D01*
X365500Y546500D01*
Y542753D01*
X360255Y537508D01*
Y533716D01*
X358797Y532258D01*
G01X508100Y605500D02*
X503600Y601000D01*
X431500D01*
X374500Y544000D01*
X372066D01*
X369316Y541250D01*
X368810D01*
X362555Y534995D01*
Y534500D01*
G01X506000Y610000D02*
X434500D01*
X373500Y549000D01*
X365500D01*
X364000Y547500D01*
Y543945D01*
X354055Y534000D01*
G01X1045500Y639500D02*
X1032500D01*
X1027450Y634450D01*
X901929D01*
X892929Y643450D01*
X863866D01*
X863716Y643300D01*
X850058D01*
X847058Y640300D01*
X802363D01*
X799712Y637649D01*
X762530D01*
X761679Y638500D01*
X758702D01*
X754602Y642600D01*
X679347D01*
X679246Y642499D01*
X675843D01*
X675341Y643001D01*
X673685D01*
X673684Y643000D01*
X609549D01*
X605999Y639450D01*
X417004D01*
X416553Y639000D01*
X416551D01*
X366051Y588500D01*
X360500D01*
G01X350000Y652878D02*
X361878D01*
X374950Y665950D01*
X382825D01*
X390753Y673878D01*
X648620D01*
X681192Y706450D01*
X691808D01*
X693758Y704500D01*
X776000D01*
X780950Y709450D01*
X799501D01*
X816501Y692450D01*
X866308D01*
X866708Y692050D01*
X882341D01*
X886291Y696000D01*
X987037D01*
X1041928Y750891D01*
Y776915D01*
X1080963Y815950D01*
X1172558D01*
X1235950Y752558D01*
Y741950D01*
X1232000Y738000D01*
G01X360024Y979100D02*
Y978272D01*
X370777Y967519D01*
X474728D01*
X481047Y961200D01*
X666400D01*
X666750Y961550D01*
G01X367665Y363430D02*
X369045Y362050D01*
X389645D01*
X389797Y362202D01*
X397657D01*
X399555Y364100D01*
X407832D01*
X408032Y363900D01*
X414565D01*
X416215Y365550D01*
X416731D01*
G01X404920Y369487D02*
X400068D01*
X396055Y373500D01*
X378299D01*
X378298Y373499D01*
X375812D01*
X375811Y373500D01*
X375237D01*
X370737Y378000D01*
X370555D01*
X368055Y380500D01*
G01X416731Y369487D02*
X415958D01*
X413135Y372310D01*
X405065D01*
X404665Y372710D01*
X403250D01*
X397960Y378000D01*
X381027D01*
X372952Y386074D01*
X371014D01*
X369931Y387157D01*
Y387623D01*
X369205Y388349D01*
X368555Y389000D01*
G01X420668Y377363D02*
X419448D01*
X416395Y374310D01*
X405895D01*
X399194Y381011D01*
X382260D01*
X375131Y388140D01*
Y389313D01*
X370763Y393681D01*
X368996D01*
X368717Y393402D01*
X368165D01*
G01X412794Y369487D02*
X411332D01*
X409509Y371310D01*
X404650D01*
X404250Y371710D01*
X402835D01*
X398045Y376500D01*
X377055D01*
X375255Y378300D01*
X374997D01*
X373855Y379442D01*
Y379700D01*
X368555Y385000D01*
G01Y376500D02*
X370115D01*
X374615Y372000D01*
X375189D01*
X375190Y371999D01*
X378920D01*
X378921Y372000D01*
X396055D01*
X400218Y367837D01*
X405745D01*
X407395Y369487D01*
X408857D01*
G01X676500Y967750D02*
Y967700D01*
X672300Y963500D01*
X482000D01*
X475681Y969819D01*
X371730D01*
X364500Y977049D01*
Y980005D01*
X364396Y980109D01*
G01X672000Y967750D02*
Y967700D01*
X669800Y965500D01*
X483000D01*
X476681Y971819D01*
X372559D01*
X366878Y977500D01*
G01X733000Y969700D02*
X677800D01*
X677500Y970000D01*
X671000D01*
X668500Y967500D01*
X484171D01*
X481171Y970500D01*
X481100D01*
X477381Y974219D01*
X373370D01*
X369200Y978389D01*
Y980252D01*
G01X667000Y969700D02*
X666800Y969500D01*
X485000D01*
X477793Y976707D01*
X381744D01*
X381632Y976819D01*
X373599D01*
X372500Y977918D01*
G01X749500Y974300D02*
X680200D01*
X679500Y975000D01*
X486500D01*
X480193Y981307D01*
X383650D01*
X377464Y987493D01*
G01X377250Y982250D02*
X379454D01*
X382697Y979007D01*
X478993D01*
X485500Y972500D01*
X678500D01*
X679000Y972000D01*
X737533D01*
X836100Y873433D01*
Y851153D01*
X921649Y765604D01*
X988981D01*
X995050Y771673D01*
Y921407D01*
X1032443Y958800D01*
X1084154D01*
X1087129Y955825D01*
X1170757D01*
X1273082Y853500D01*
X1311758D01*
X1314300Y850958D01*
Y844453D01*
X1318450Y840303D01*
Y802149D01*
X1310500Y794199D01*
Y776682D01*
X1305500Y771682D01*
Y740250D01*
X1305000Y739750D01*
G01X443910Y174041D02*
X445569Y175700D01*
Y184164D01*
X438733Y191000D01*
X393085D01*
X391853Y192232D01*
Y212493D01*
X392860Y213500D01*
X397528D01*
X401453Y217425D01*
Y231047D01*
X395500Y237000D01*
G01X389500Y319150D02*
X391150Y320800D01*
X395790D01*
X396290Y321300D01*
X403789D01*
X403989Y321500D01*
X404555D01*
X411522Y328467D01*
X413478D01*
X414444Y329433D01*
Y330164D01*
X416584Y332304D01*
X417315D01*
X418481Y333470D01*
Y334926D01*
X420668Y337113D01*
Y337991D01*
G01X392589Y317729D02*
X392860Y318000D01*
X393137D01*
X394437Y319300D01*
X395790D01*
X396240Y319750D01*
X402280D01*
X403530Y318500D01*
X409889D01*
X418481Y327092D01*
Y330264D01*
X420521Y332304D01*
X421252D01*
X422418Y333470D01*
Y335363D01*
X424605Y337550D01*
Y337991D01*
G01X394055Y335000D02*
X394684Y335629D01*
X395426D01*
X395797Y336000D01*
X401320D01*
X406715Y341395D01*
Y342261D01*
X408569Y344115D01*
X409582D01*
X410145Y344678D01*
X417006D01*
X420328Y348000D01*
X426055D01*
X427857Y349802D01*
X428542D01*
G01X391325Y324520D02*
X396535D01*
X397422Y323633D01*
X401207D01*
X407107Y329533D01*
Y330701D01*
X408273Y331867D01*
X409004D01*
X411044Y333907D01*
Y334638D01*
X412210Y335804D01*
X412941D01*
X414544Y337407D01*
Y338138D01*
X416584Y340178D01*
X417456D01*
X419206Y341928D01*
X420668D01*
G01X416731Y337991D02*
X414544Y335804D01*
Y333470D01*
X413378Y332304D01*
X412647D01*
X411044Y330701D01*
Y329970D01*
X403374Y322300D01*
X390554D01*
X386755Y326100D01*
G01X382455Y331870D02*
X390324D01*
X392044Y330150D01*
X399413D01*
X402733Y333470D01*
Y334201D01*
X406882Y338350D01*
X407613D01*
X410607Y341344D01*
Y342075D01*
X412210Y343678D01*
X418481D01*
X420668Y345865D01*
G01X416731Y341928D02*
X415983D01*
X414233Y340178D01*
X412647D01*
X406670Y334201D01*
Y333470D01*
X405067Y331867D01*
X404195D01*
X400978Y328650D01*
X391355D01*
X390555Y329450D01*
X384798D01*
X384160Y328812D01*
G01X388500Y400575D02*
X388925D01*
X390500Y399000D01*
X396055D01*
X400055Y395000D01*
X413555D01*
X415444Y393111D01*
X416731D01*
G01X390543Y391950D02*
X391493Y391000D01*
X397555D01*
X399233Y389322D01*
Y388449D01*
X400258Y387424D01*
X401131D01*
X405068Y383487D01*
X417456D01*
X419206Y385237D01*
X420668D01*
G01X387000Y404275D02*
X393000D01*
X394103Y403172D01*
X410727D01*
X412477Y404922D01*
X412794D01*
G01X420668Y397048D02*
Y397323D01*
X419018Y398973D01*
Y409543D01*
X419481Y410006D01*
Y425747D01*
X403628Y441600D01*
X401613D01*
X393055Y450158D01*
Y451000D01*
G01Y447400D02*
X399855Y440600D01*
X403213D01*
X418481Y425332D01*
Y412481D01*
X418381Y412381D01*
Y412112D01*
X417415Y411146D01*
X417146D01*
X414500Y408500D01*
Y403216D01*
X416731Y400985D01*
G01X385463Y450948D02*
X386107D01*
X386555Y450500D01*
X389797D01*
X392247Y452950D01*
X393863D01*
X395005Y451808D01*
Y450495D01*
X402900Y442600D01*
X404043D01*
X420481Y426162D01*
Y413519D01*
X422500Y411500D01*
Y391279D01*
X424605Y389174D01*
G01X402953Y23622D02*
X411620Y32289D01*
X437211D01*
X471422Y66500D01*
X537000D01*
X573450Y102950D01*
X651308D01*
X664798Y89460D01*
Y87202D01*
X686000Y66000D01*
Y62000D01*
G01X428542Y357676D02*
X426892Y359326D01*
X423921D01*
X422318Y357723D01*
Y356992D01*
X421252Y355926D01*
X420521D01*
X418481Y353886D01*
Y353155D01*
X417315Y351989D01*
X416340D01*
X414565Y350214D01*
Y349276D01*
X413499Y348210D01*
X411902D01*
X410497Y349615D01*
X406524D01*
X400055Y343146D01*
G01X420668Y349802D02*
X417076Y346210D01*
X410987D01*
X409682Y347515D01*
X408026D01*
X403314Y342803D01*
Y341708D01*
X399239Y337633D01*
X396422D01*
X396055Y338000D01*
G01X423425Y23622D02*
X449016D01*
X487894Y62500D01*
X538500D01*
X573800Y97800D01*
X644820D01*
X645070Y97550D01*
X646450D01*
X682000Y62000D01*
Y58687D01*
X685519Y55168D01*
Y55019D01*
G01X413189Y23622D02*
X416988Y27421D01*
X442579D01*
X479658Y64500D01*
X538000D01*
X572800Y99300D01*
X645442D01*
X645692Y99050D01*
X647450D01*
X684050Y62450D01*
Y59395D01*
X684861Y58584D01*
G01X619876Y195000D02*
X616876Y192000D01*
X615248D01*
X590248Y167000D01*
X554500D01*
X528500Y141000D01*
X493671D01*
X474887Y122216D01*
Y119200D01*
X471737Y116050D01*
X420005D01*
X418192Y114237D01*
G01X899000Y312500D02*
Y273167D01*
X862333Y236500D01*
X794500D01*
X791650Y239350D01*
X660476D01*
X589626Y168500D01*
X553171D01*
X527171Y142500D01*
X491941D01*
X472291Y122850D01*
X441687D01*
X438572Y119735D01*
X428375D01*
G01X443910Y174041D02*
X441174D01*
X437481Y170348D01*
X433700D01*
X431038Y167686D01*
X425822D01*
X420226Y162090D01*
Y160722D01*
X436259Y144689D01*
X437764D01*
X439249Y143204D01*
Y135537D01*
X435712Y132000D01*
X422756D01*
X418940Y128184D01*
Y125000D01*
G01X439540Y124500D02*
X439690Y124350D01*
X471669D01*
X491319Y144000D01*
X526484D01*
X552484Y170000D01*
X589004D01*
X659854Y240850D01*
X796832D01*
X799682Y238000D01*
X861711D01*
X896000Y272289D01*
Y314000D01*
X898000Y316000D01*
G01X528500Y310000D02*
Y305603D01*
X520313Y297416D01*
Y292210D01*
X501603Y273500D01*
X479755D01*
X469055Y262800D01*
X463850D01*
X461100Y260050D01*
G01X534500Y295500D02*
Y294500D01*
X528530Y288530D01*
X527085D01*
X504277Y265722D01*
X482222D01*
X470800Y254300D01*
X463426D01*
X459055Y258671D01*
Y263500D01*
G01X534629Y311171D02*
Y308413D01*
X522313Y296096D01*
Y291381D01*
X502432Y271500D01*
X481555D01*
X469455Y259400D01*
X466700D01*
G01X531590Y297620D02*
X503470Y269500D01*
X482384D01*
X469384Y256500D01*
X464055D01*
G01X508100Y605500D02*
X554500D01*
X558900Y601100D01*
X667097D01*
X670047Y598150D01*
X827350D01*
X833800Y591700D01*
X998300D01*
X998500Y591500D01*
G01X1038000Y604000D02*
X1035036Y601036D01*
X833344D01*
X832430Y601950D01*
X678550D01*
X675500Y605000D01*
X574000D01*
X569000Y610000D01*
X506000D01*
G01X826198Y239950D02*
X823298Y242850D01*
X659732D01*
X588382Y171500D01*
X550700D01*
X533000Y153800D01*
G01X548000Y369500D02*
X561545D01*
X562214Y370169D01*
X563337Y371289D01*
X570755D01*
X579294Y362750D01*
X721250D01*
X739880Y344120D01*
X856360D01*
X861055Y348815D01*
X900122D01*
X919757Y368450D01*
X1018500D01*
X1031000Y355950D01*
G01X559500Y604500D02*
X560600Y603400D01*
X668050D01*
X671000Y600450D01*
X831808D01*
X837758Y594500D01*
X1035000D01*
G01X1027426Y346500D02*
Y346571D01*
X1007547Y366450D01*
X920939D01*
X899404Y344915D01*
X860166D01*
X857371Y342120D01*
X738880D01*
X721000Y360000D01*
X579213D01*
X570712Y368501D01*
X565052D01*
X564215Y369339D01*
G01X1023000Y347000D02*
Y347071D01*
X1010121Y359950D01*
X917268D01*
X900038Y342720D01*
X860800D01*
X855230Y337150D01*
X741021D01*
X720171Y358000D01*
X578384D01*
X570383Y366001D01*
X566929D01*
X566430Y366500D01*
G01X1031000Y348500D02*
Y347316D01*
X1028234Y344550D01*
X1022692D01*
X1009292Y357950D01*
X918450D01*
X897500Y337000D01*
X863459D01*
X861609Y335150D01*
X740192D01*
X719342Y356000D01*
X577555D01*
X569555Y364000D01*
G01X619876Y195000D02*
X623500Y198624D01*
Y200252D01*
X651748Y228500D01*
X864100D01*
X902500Y266900D01*
Y323250D01*
X903480Y324230D01*
G01X622500Y608500D02*
X693829D01*
X694379Y607950D01*
X897000D01*
X899000Y609950D01*
X1064879D01*
X1130329Y544500D01*
X1148842D01*
X1173042Y520300D01*
X1196363D01*
X1198362Y522299D01*
X1222154D01*
X1222155Y522300D01*
X1230487D01*
X1231537Y523350D01*
X1233500D01*
X1241282Y531132D01*
Y533095D01*
X1263179Y554992D01*
Y578679D01*
X1272000Y587500D01*
X1287432D01*
X1289432Y589500D01*
Y592951D01*
X1288335Y594048D01*
G01X622500Y696500D02*
X641500D01*
X670500Y725500D01*
X769500D01*
X774500Y730500D01*
X816000D01*
X829450Y717050D01*
X987899D01*
X1031428Y760579D01*
Y803686D01*
X1034742Y807000D01*
X1042492D01*
X1095418Y859926D01*
Y904541D01*
X1097423Y906546D01*
G01X673300Y579000D02*
X703313D01*
X703863Y579550D01*
X707137D01*
X708954Y577733D01*
X729154D01*
X729887Y577000D01*
X742000D01*
X748638Y583638D01*
X810862D01*
X813000Y581500D01*
X1036500D01*
G01X669000Y579000D02*
X671000Y577000D01*
X704142D01*
X704692Y577550D01*
X706308D01*
X708125Y575733D01*
X728325D01*
X729058Y575000D01*
X746500D01*
X753138Y581638D01*
X808862D01*
X811500Y579000D01*
X1040000D01*
G01X1287482Y590500D02*
X1270500D01*
X1261179Y581179D01*
Y555821D01*
X1239282Y533924D01*
Y531961D01*
X1232671Y525350D01*
X1230708D01*
X1229658Y524300D01*
X1221326D01*
X1221325Y524299D01*
X1197533D01*
X1195534Y522300D01*
X1173871D01*
X1149671Y546500D01*
X1132000D01*
X1066550Y611950D01*
X898171D01*
X896171Y609950D01*
X695208D01*
X691208Y613950D01*
X672950D01*
X669500Y610500D01*
X663500D01*
G01X674688Y696751D02*
X723339Y648100D01*
X757737D01*
X764188Y641649D01*
X798054D01*
X803705Y647300D01*
X862058D01*
X862208Y647450D01*
X894587D01*
X903587Y638450D01*
X979797D01*
X985597Y644250D01*
X1043492D01*
X1045192Y645950D01*
X1078292D01*
X1100563Y623679D01*
X1127513D01*
X1130490Y626656D01*
Y627436D01*
G01X1143500Y542000D02*
X1130000D01*
X1064050Y607950D01*
X932004D01*
X930004Y605950D01*
X693550D01*
X693500Y606000D01*
X688500D01*
G01X683000Y603950D02*
X930833D01*
X932833Y605950D01*
X1056808D01*
X1057950Y604808D01*
Y602492D01*
X1061192Y599250D01*
X1069921D01*
X1129171Y540000D01*
X1145500D01*
X1147500Y542000D01*
G01X680000Y640000D02*
X680300Y640300D01*
X753649D01*
X761099Y632850D01*
X800995D01*
X801795Y633650D01*
X896647D01*
X904647Y625650D01*
X1058932D01*
X1129082Y555500D01*
X1172000D01*
X1173500Y554000D01*
G01X677500Y699000D02*
X726700Y649800D01*
X758442D01*
X764893Y643349D01*
X797349D01*
X805200Y651200D01*
X893242D01*
X904292Y640150D01*
X979092D01*
X985442Y646500D01*
X1006817D01*
X1010567Y650250D01*
X1012433D01*
X1016133Y646550D01*
X1043387D01*
X1044487Y647650D01*
X1078997D01*
X1101268Y625379D01*
X1126808D01*
X1127950Y626521D01*
Y627950D01*
X1131000Y631000D01*
G01X1037000Y734000D02*
X1036500D01*
X993700Y691200D01*
X903613D01*
X900963Y688550D01*
X818279D01*
X798879Y707950D01*
X787950D01*
X783000Y703000D01*
X692500D01*
X691000Y704500D01*
G01X679000Y865050D02*
X685400Y871450D01*
X821670D01*
X824560Y868560D01*
G01X702559Y290355D02*
X703000Y290796D01*
Y310000D01*
X707000Y314000D01*
Y316613D01*
X713887Y323500D01*
X852788D01*
X864288Y335000D01*
X899000D01*
X919950Y355950D01*
X1008050D01*
X1021450Y342550D01*
X1029063D01*
X1033000Y346487D01*
Y394500D01*
X1026000Y401500D01*
Y407796D01*
X998996Y434800D01*
X988900D01*
G01X691300Y807300D02*
X714700D01*
X718500Y803500D01*
X846411D01*
X910411Y739500D01*
X994745D01*
X1019518Y764273D01*
Y867776D01*
X1022750Y871008D01*
Y887933D01*
X1020500Y890183D01*
Y908242D01*
X1018332Y910410D01*
Y918520D01*
X1037662Y937850D01*
X1158908D01*
X1288000Y808758D01*
Y739050D01*
X1305300Y721750D01*
Y673159D01*
X1310425Y668034D01*
Y660062D01*
G01X832479Y298230D02*
X830749Y296500D01*
X823500D01*
X812500Y307500D01*
Y309500D01*
X809000Y313000D01*
Y316500D01*
X804500Y321000D01*
X717500D01*
X714369Y317869D01*
Y308070D01*
G01X722000Y808500D02*
Y808450D01*
X724950Y805500D01*
X847242D01*
X911242Y741500D01*
X993916D01*
X1017150Y764734D01*
Y908763D01*
X1016332Y909581D01*
Y919349D01*
X1036833Y939850D01*
X1159737D01*
X1291162Y808425D01*
Y739338D01*
X1309000Y721500D01*
Y672288D01*
X1312425Y668863D01*
Y657725D01*
X1311100Y656400D01*
G01X766000Y635000D02*
X766150Y635150D01*
X800042D01*
X801392Y636500D01*
X859745D01*
X864695Y641450D01*
X892100D01*
X901401Y632149D01*
X1064351D01*
X1074900Y621600D01*
X1121500D01*
G01X1070000Y650725D02*
X1014363D01*
X1013138Y651950D01*
X1009862D01*
X1008684Y650772D01*
X987309D01*
X978387Y641850D01*
X908108D01*
X897058Y652900D01*
X804158D01*
X796307Y645049D01*
X765951D01*
X763000Y648000D01*
G01X767000Y648500D02*
X768751Y646749D01*
X784431D01*
X796932Y659250D01*
X900392D01*
X916092Y643550D01*
X977682D01*
X988982Y654850D01*
X1012643D01*
X1014818Y652675D01*
X1076377D01*
X1091052Y638000D01*
X1117000D01*
X1124000Y631000D01*
X1125041D01*
G01X1299000Y641500D02*
Y647247D01*
X1302000Y650247D01*
Y668255D01*
X1299500Y670755D01*
Y716000D01*
X1285500Y730000D01*
Y800758D01*
X1150708Y935550D01*
X1038615D01*
X1023466Y920401D01*
Y890470D01*
X1025050Y888886D01*
Y860918D01*
X1022482Y858350D01*
Y763372D01*
X996310Y737200D01*
X906547D01*
X898447Y745300D01*
X759300D01*
X757500Y743500D01*
G01X870100Y237500D02*
X867100Y234500D01*
X790837D01*
X789500Y235837D01*
G01X780000Y250000D02*
X867347D01*
X884400Y267053D01*
Y294559D01*
X880729Y298230D01*
X871849D01*
G01X1209500Y514000D02*
X1201379D01*
X1199679Y512300D01*
X1168200D01*
X1149000Y531500D01*
X1122171D01*
X1082921Y570750D01*
X791438D01*
X786500Y575688D01*
G01X1213100Y514000D02*
X1212500D01*
X1208800Y510300D01*
X1167200D01*
X1148000Y529500D01*
X1121342D01*
X1082892Y567950D01*
X788550D01*
X786032Y570468D01*
G01X1196500Y736687D02*
X1182713D01*
X1161900Y757500D01*
X1123082D01*
X1098582Y782000D01*
X1062242D01*
X1059250Y779008D01*
Y753658D01*
X1054400Y748808D01*
Y748642D01*
X994958Y689200D01*
X904442D01*
X901792Y686550D01*
X817450D01*
X798000Y706000D01*
G01X820669Y315945D02*
X824415Y319691D01*
X851808D01*
X865117Y333000D01*
X905329D01*
X920879Y348550D01*
X953123D01*
X953500Y348927D01*
G01X1128149Y525261D02*
X1126488Y523600D01*
X1122008D01*
X1082176Y563432D01*
X824382D01*
X823000Y562050D01*
X817850D01*
X815900Y564000D01*
G01X1130928Y527550D02*
Y527500D01*
X1120513D01*
X1082063Y565950D01*
X821450D01*
X819500Y564000D01*
G01X826500Y743000D02*
X897494D01*
X905594Y734900D01*
X997263D01*
X1024782Y762419D01*
Y855647D01*
X1027350Y858215D01*
Y889839D01*
X1025766Y891423D01*
Y919448D01*
X1039568Y933250D01*
X1148054D01*
X1206500Y874804D01*
Y874242D01*
X1208242Y872500D01*
X1209758D01*
X1283000Y799258D01*
Y728500D01*
X1297200Y714300D01*
Y669802D01*
X1299700Y667302D01*
Y651200D01*
X1296700Y648200D01*
Y639200D01*
X1296000Y638500D01*
G01X852164Y315945D02*
Y317218D01*
X865946Y331000D01*
X906158D01*
X921658Y346500D01*
X954312D01*
X959500Y351688D01*
G01X856104Y308070D02*
Y318329D01*
X864995Y327220D01*
X905207D01*
X922487Y344500D01*
X955141D01*
X964000Y353359D01*
Y354000D01*
G01X937000Y489000D02*
X871000D01*
X867500Y485500D01*
X857500D01*
G01X1267500Y675000D02*
X1270250Y672250D01*
Y666250D01*
X1275355Y661145D01*
Y638995D01*
X1273301Y636941D01*
Y617043D01*
X1271758Y615500D01*
X1271160D01*
X1265000Y609340D01*
Y609159D01*
X1248550Y592709D01*
Y555821D01*
X1251623Y552748D01*
Y549218D01*
X1237282Y534877D01*
Y532790D01*
X1231842Y527350D01*
X1229755D01*
X1228705Y526300D01*
X1220497D01*
X1220496Y526299D01*
X1196704D01*
X1194705Y524300D01*
X1174700D01*
X1150500Y548500D01*
X1132829D01*
X1058579Y622750D01*
X901250D01*
X894500Y629500D01*
X859500D01*
G01X860718Y683684D02*
X861284Y684250D01*
X999992D01*
X1085392Y769650D01*
X1104850D01*
X1125072Y749428D01*
X1125884D01*
X1127812Y747500D01*
X1146334D01*
X1164907Y728927D01*
Y726593D01*
X1171500Y720000D01*
G01X924465Y388465D02*
Y389635D01*
X893000Y421100D01*
Y426500D01*
X893500Y427000D01*
G01X903075Y472000D02*
X903800D01*
X936300Y439500D01*
X982075D01*
G01X1260500Y546400D02*
X1257984D01*
X1243282Y531698D01*
Y530303D01*
X1233278Y520299D01*
X1199191D01*
X1197192Y518300D01*
X1172213D01*
X1152513Y538000D01*
X1128342D01*
X1069092Y597250D01*
X1060363D01*
X1060313Y597300D01*
X935400D01*
G01X944000Y434000D02*
X982870D01*
X985970Y437100D01*
X1000007D01*
X1038050Y399057D01*
Y335550D01*
X975007Y272507D01*
Y194300D01*
G01X1022000Y492500D02*
Y488000D01*
X1015551Y481551D01*
X1013323D01*
X1010949Y479177D01*
Y461949D01*
X1006950Y457950D01*
Y440550D01*
X1042850Y404650D01*
Y331350D01*
X982910Y271410D01*
Y190757D01*
X972853Y180700D01*
X959900D01*
G01X1081000Y544400D02*
X1032864D01*
X1025814Y551450D01*
X980950D01*
X977000Y547500D01*
G01X1084599Y544520D02*
X1084420D01*
X1082350Y542450D01*
X1032050D01*
X1027500Y547000D01*
X985000D01*
X982500Y549500D01*
G01X1081000Y548000D02*
X1032158D01*
X1026658Y553500D01*
X978500D01*
X978000Y554000D01*
G01X1013500Y559000D02*
X1053310D01*
X1060885Y551425D01*
X1091425D01*
G01X1016900Y561000D02*
X1053432D01*
X1058432Y556000D01*
X1086000D01*
G01X1011500Y667500D02*
X1023950Y655050D01*
X1047332D01*
X1049284Y657002D01*
X1074881D01*
X1091883Y640000D01*
X1093500D01*
G01X1078500Y464000D02*
X1057116Y442616D01*
Y363634D01*
X1058250Y362500D01*
Y324342D01*
X1049400Y315492D01*
Y288900D01*
X1038550Y278050D01*
Y247867D01*
X1033900Y243217D01*
Y225500D01*
G01X1199500Y743500D02*
X1182500D01*
X1164500Y761500D01*
X1126087D01*
X1099137Y788450D01*
X1062963D01*
X1049000Y774487D01*
Y751054D01*
X1026946Y729000D01*
X1025500D01*
X1023500Y727000D01*
G01X1035000Y800000D02*
X1042000D01*
X1080500Y838500D01*
X1156256D01*
X1156257Y838499D01*
X1157499D01*
X1166689Y847689D01*
Y854689D01*
X1168000Y856000D01*
X1169000D01*
G01X1035000Y804500D02*
X1044378D01*
X1079878Y840000D01*
X1156878D01*
X1165189Y848311D01*
Y856811D01*
X1164500Y857500D01*
G01X1124327Y465391D02*
X1103436Y444500D01*
X1066467D01*
X1058816Y436849D01*
Y365634D01*
X1059950Y364500D01*
Y320950D01*
X1053000Y314000D01*
Y287000D01*
X1040250Y274250D01*
Y247162D01*
X1037500Y244412D01*
Y225500D01*
G01X1038500Y706500D02*
X1053020D01*
X1054020Y705500D01*
X1125467D01*
X1126093Y704874D01*
G01X1184500Y772782D02*
X1182000Y775282D01*
Y791033D01*
X1167101Y805932D01*
X1076603D01*
X1046000Y775329D01*
Y750812D01*
X1040208Y745020D01*
G01X1188500Y773000D02*
X1188000D01*
X1186700Y774300D01*
Y795827D01*
X1170677Y811850D01*
X1113108D01*
X1112642Y811384D01*
X1098874D01*
X1096308Y813950D01*
X1081792D01*
X1044000Y776158D01*
Y763940D01*
G01X1249773Y551500D02*
X1249500Y551227D01*
Y549500D01*
X1235582Y535582D01*
Y533495D01*
X1231137Y529050D01*
X1229050D01*
X1228000Y528000D01*
X1219792D01*
X1219791Y527999D01*
X1195999D01*
X1194000Y526000D01*
X1188409D01*
X1175801Y538608D01*
Y554952D01*
X1169728Y561025D01*
X1135267D01*
X1134292Y560050D01*
X1131192D01*
X1117885Y573357D01*
Y575000D01*
X1062940Y629945D01*
G01X1054080Y680630D02*
X1059842Y674868D01*
X1127362D01*
X1127438Y674944D01*
G01X1132440Y676555D02*
X1131624D01*
X1127773Y680406D01*
X1127771D01*
X1126805Y681372D01*
X1125437D01*
X1124599Y680534D01*
X1072466D01*
X1069596Y683404D01*
X1060304D01*
X1058350Y681450D01*
G01X1054500Y697000D02*
X1058000Y693500D01*
X1068500D01*
X1072364Y689636D01*
X1073150D01*
X1073581Y689205D01*
X1075197D01*
X1075392Y689400D01*
X1122052D01*
X1123905Y687547D01*
G01X1052500Y693000D02*
X1055000Y690500D01*
X1066500D01*
X1068050Y688950D01*
X1069308D01*
X1073154Y685104D01*
X1112470D01*
X1115340Y682234D01*
X1116173D01*
X1116193Y682214D01*
X1124864D01*
X1125022Y682372D01*
X1127220D01*
X1128438Y681154D01*
X1130318D01*
X1130358Y681194D01*
G01X1135594Y679704D02*
X1135685Y679613D01*
G01X1120030Y703370D02*
X1117474Y700814D01*
X1076186D01*
X1075450Y701550D01*
X1073192D01*
X1071568Y703174D01*
X1053588D01*
X1052678Y704084D01*
G01X1052500Y709000D02*
X1052864D01*
X1053664Y708200D01*
X1053725D01*
X1054545Y707380D01*
X1071498D01*
X1073792Y709674D01*
X1075408D01*
X1077702Y707380D01*
X1121570D01*
X1122280Y706670D01*
G01X1052500Y700000D02*
Y699984D01*
X1052600Y699884D01*
X1068616D01*
X1071796Y696704D01*
X1092269D01*
X1092700Y697135D01*
X1128385D01*
X1128606Y696914D01*
X1130544D01*
X1132194Y698564D01*
X1132440D01*
G01X1140710Y707750D02*
Y705271D01*
X1138889Y703450D01*
X1137633D01*
X1133022Y708061D01*
G01X1122633Y709930D02*
X1078405D01*
X1076098Y712237D01*
Y712432D01*
X1074956Y713574D01*
X1073340D01*
X1072198Y712432D01*
Y711333D01*
X1070795Y709930D01*
X1055442D01*
X1052648Y712724D01*
G01X1123010Y712793D02*
X1084397D01*
X1078190Y719000D01*
X1060540D01*
X1059800Y719740D01*
G01X1052500Y773350D02*
X1057250Y778100D01*
Y779837D01*
X1063863Y786450D01*
X1098308D01*
X1125258Y759500D01*
X1162729D01*
X1181729Y740500D01*
X1200742D01*
X1223742Y717500D01*
X1227500D01*
X1229000Y716000D01*
G01X1063000Y780000D02*
X1097000D01*
X1105050Y771950D01*
X1105803D01*
X1122253Y755500D01*
X1145824D01*
X1178149Y723175D01*
Y715988D01*
X1176503Y714342D01*
G01X1080000Y520000D02*
X1122000D01*
X1123500Y521500D01*
G01X1093894Y126500D02*
X1093867Y126528D01*
G02X1092511Y129800I3272J3273D01*
G01Y139718D01*
G03X1091400Y142400I-3793J0D01*
G01X1091207Y142593D01*
G02X1090500Y144300I1707J1707D01*
G01Y159669D01*
G02X1090795Y160259I789J-26D01*
G03X1091090Y160849I-495J616D01*
G01Y162349D01*
G03X1090795Y162939I-789J-26D01*
G02X1090500Y163529I495J616D01*
G01Y170598D01*
G02X1090795Y171188I790J-26D01*
G03X1091090Y171778I-495J616D01*
G01Y173278D01*
G03X1090795Y173868I-790J-26D01*
G02X1090500Y174458I495J616D01*
G01Y175958D01*
G02X1090795Y176548I790J-26D01*
G03X1091090Y177138I-495J616D01*
G01Y178638D01*
G03X1090795Y179228I-790J-26D01*
G02X1090500Y179818I495J616D01*
G01Y189615D01*
G02X1090795Y190205I790J-26D01*
G03X1091090Y190795I-494J616D01*
G01Y192295D01*
G03X1090795Y192885I-790J-26D01*
G02X1090500Y193475I494J616D01*
G01Y194975D01*
G02X1090795Y195565I790J-26D01*
G03X1091090Y196155I-494J616D01*
G01Y197655D01*
G03X1090795Y198245I-790J-26D01*
G02X1090500Y198835I494J616D01*
G01Y200335D01*
G02X1090795Y200925I790J-26D01*
G03X1091090Y201515I-494J616D01*
G01Y203015D01*
G03X1090795Y203605I-790J-26D01*
G02X1090500Y204195I494J616D01*
G01Y209100D01*
G02X1092551Y214050I7001J-1D01*
G01X1104869Y226369D01*
G03X1106000Y229100I-2732J2731D01*
G01Y296964D01*
G02X1106732Y298732I2500J0D01*
G01X1153446Y345446D01*
G03X1154500Y347991I-2546J2545D01*
G01Y363000D01*
G03X1153440Y365560I-3621J0D01*
G01X1152600Y366400D01*
G02X1152100Y367607I1207J1207D01*
G01Y426567D01*
G02X1152833Y428335I2500J-1D01*
G01X1159045Y434544D01*
G03X1160100Y437090I-2545J2546D01*
G01Y446866D01*
G03X1157591Y449375I-2509J0D01*
G01X1157090D01*
G02X1156737Y449521I0J500D01*
G01X1155500Y450758D01*
G01X1090028Y126500D02*
X1090055Y126528D01*
G03X1091411Y129800I-3272J3273D01*
G01Y139717D01*
G03X1090622Y141622I-2693J1D01*
G01X1090429Y141815D01*
G02X1089400Y144300I2486J2485D01*
G01Y209101D01*
G02X1091773Y214828I8101J-1D01*
G01X1104091Y227147D01*
G03X1104900Y229100I-1953J1953D01*
G01Y296965D01*
G02X1105954Y299510I3600J0D01*
G01X1152668Y346224D01*
G03X1153400Y347992I-1768J1768D01*
G01Y363000D01*
G03X1152662Y364782I-2520J0D01*
G01X1151822Y365622D01*
G02X1151000Y367606I1985J1985D01*
G01Y426567D01*
G02X1152055Y429113I3600J0D01*
G01X1158267Y435322D01*
G03X1159000Y437090I-1767J1768D01*
G01Y446866D01*
G03X1157591Y448275I-1409J0D01*
G01X1157090D01*
G03X1156737Y448129I0J-500D01*
G01X1155500Y446892D01*
G01X1093500Y640000D02*
X1118799D01*
X1126991Y631808D01*
Y630141D01*
X1126000Y629150D01*
Y627329D01*
G01X1094500Y657500D02*
X1108850Y643150D01*
X1118150D01*
X1137182Y662182D01*
G01X1091000Y692519D02*
X1093916Y695435D01*
X1126157D01*
G01X1114883Y591925D02*
Y589934D01*
X1118679Y586138D01*
X1134118D01*
X1141592Y593612D01*
Y604421D01*
X1164500Y627329D01*
Y628723D01*
G01X1114500Y645000D02*
X1119500Y650000D01*
Y653700D01*
X1131000Y665200D01*
G01X1130000Y361500D02*
Y335500D01*
X1132500Y333000D01*
G01X1159075Y630600D02*
Y627562D01*
X1125500Y593987D01*
Y590657D01*
X1122931Y588088D01*
X1119487D01*
G01X1154847Y630908D02*
X1126950Y603011D01*
Y602242D01*
X1122353Y597645D01*
Y590268D01*
G01X1146500Y267000D02*
Y272500D01*
X1150000Y276000D01*
Y295823D01*
X1150500Y296323D01*
Y299242D01*
X1161050Y309792D01*
Y309812D01*
X1163000Y311762D01*
Y326000D01*
X1178500Y341500D01*
Y348829D01*
X1182000Y352329D01*
Y357000D01*
G01X1146000Y258500D02*
X1149050Y261550D01*
Y272050D01*
X1152000Y275000D01*
Y294994D01*
X1163050Y306044D01*
Y308983D01*
X1164192Y310125D01*
X1165397D01*
X1167268Y311996D01*
X1169002D01*
X1180500Y323494D01*
Y348000D01*
X1184000Y351500D01*
G01X1144425Y325500D02*
Y331374D01*
X1154454Y341403D01*
Y341503D01*
X1159430Y346479D01*
Y362428D01*
X1158108Y363750D01*
Y365779D01*
X1160000Y367671D01*
Y405500D01*
X1166500Y412000D01*
Y415500D01*
G01X1139632Y594441D02*
X1139592D01*
Y605250D01*
X1161075Y626733D01*
Y644267D01*
X1158748Y646594D01*
Y658807D01*
X1160748Y660807D01*
G01X1140500Y589000D02*
X1142200Y590700D01*
Y591351D01*
X1143632Y592783D01*
Y603632D01*
X1166500Y626500D01*
Y641671D01*
X1160748Y647423D01*
Y657657D01*
G01X1143000Y629000D02*
X1147000Y633000D01*
Y638500D01*
X1148150Y639650D01*
Y663956D01*
G01X1151000Y264500D02*
X1154100D01*
X1157100Y267500D01*
Y285151D01*
X1184500Y312551D01*
Y345000D01*
X1188000Y348500D01*
Y376500D01*
X1185550Y378950D01*
Y449050D01*
X1234746Y498246D01*
Y499135D01*
X1249778Y514167D01*
X1257414D01*
X1295500Y552253D01*
Y563184D01*
X1300000Y567684D01*
Y592658D01*
X1286658Y606000D01*
X1274500D01*
G01X1278500Y603500D02*
X1286329D01*
X1298000Y591829D01*
Y568513D01*
X1293500Y564013D01*
Y553082D01*
X1256585Y516167D01*
X1248949D01*
X1233028Y500246D01*
X1232012D01*
X1218000Y486234D01*
Y484329D01*
X1180550Y446879D01*
Y405950D01*
X1183500Y403000D01*
Y377500D01*
X1186000Y375000D01*
Y349500D01*
X1182500Y346000D01*
Y314000D01*
X1154000Y285500D01*
Y268000D01*
X1153700Y267700D01*
G01X1157700Y368500D02*
X1157701Y368501D01*
Y369872D01*
X1158000Y370171D01*
Y413000D01*
X1167550Y422550D01*
Y450721D01*
X1201000Y484171D01*
Y487000D01*
X1214500Y500500D01*
Y509000D01*
X1214450D01*
G01X1155400Y371500D02*
X1156000Y372100D01*
Y415300D01*
X1165550Y424850D01*
Y451550D01*
X1199000Y485000D01*
Y488171D01*
X1212500Y501671D01*
Y509829D01*
X1215671Y513000D01*
X1220500D01*
G01X1162348Y656923D02*
X1163000Y656271D01*
Y648500D01*
X1174500Y637000D01*
Y613226D01*
X1186050Y601676D01*
Y555379D01*
X1181550Y550879D01*
Y535688D01*
X1189238Y528000D01*
X1191000D01*
G01X1167098Y663932D02*
Y652402D01*
X1179500Y640000D01*
Y633671D01*
X1181000Y632171D01*
Y627171D01*
X1182171Y626000D01*
X1184484D01*
X1190050Y620434D01*
Y552625D01*
X1185500Y548075D01*
G01X1177100Y624750D02*
Y625400D01*
X1176500Y626000D01*
Y639830D01*
X1165330Y651000D01*
Y659370D01*
G01X1169300Y663120D02*
Y655700D01*
X1181500Y643500D01*
Y634500D01*
X1185764Y630236D01*
X1185906D01*
X1194050Y622092D01*
Y553950D01*
X1200075Y547925D01*
X1200500D01*
G01X1162000Y960625D02*
X1168768D01*
X1168769Y960626D01*
X1176592D01*
X1272218Y865000D01*
X1316318D01*
X1337500Y843818D01*
Y664500D01*
X1334500Y661500D01*
Y636000D01*
G01X1182000Y357000D02*
Y372358D01*
X1179500Y374858D01*
Y398500D01*
X1176550Y401450D01*
Y450879D01*
X1209000Y483329D01*
Y486329D01*
X1226171Y503500D01*
X1226754D01*
X1227500Y504246D01*
G01X1249251Y528688D02*
X1249282D01*
Y527816D01*
X1235765Y514299D01*
X1231312D01*
X1203000Y485987D01*
Y483342D01*
X1169550Y449892D01*
Y401450D01*
X1174260Y396740D01*
Y386847D01*
X1172550Y385137D01*
Y381863D01*
X1175500Y378913D01*
Y373200D01*
X1177075Y371625D01*
Y359175D01*
X1174400Y356500D01*
G01X1178000D02*
X1179075Y357575D01*
Y372454D01*
X1177500Y374029D01*
Y379742D01*
X1174550Y382692D01*
Y384308D01*
X1176260Y386018D01*
Y397740D01*
X1171550Y402450D01*
Y449063D01*
X1205000Y482513D01*
Y485158D01*
X1226088Y506246D01*
X1230541D01*
X1246462Y522167D01*
X1246667D01*
X1251500Y527000D01*
Y531500D01*
G01X1227500Y500500D02*
X1226000D01*
X1216000Y490500D01*
Y485158D01*
X1178550Y447708D01*
Y402450D01*
X1181500Y399500D01*
Y376000D01*
X1184000Y373500D01*
Y351500D01*
G01X1186000Y615500D02*
X1188050Y613450D01*
Y554550D01*
X1183550Y550050D01*
Y536629D01*
X1187050Y533129D01*
Y533017D01*
X1188192Y531875D01*
X1188304D01*
X1189243Y530936D01*
X1194564D01*
G01X1189000Y533825D02*
X1192050Y536875D01*
Y621263D01*
X1185313Y628000D01*
X1183000D01*
G01X1179662Y673421D02*
X1181083Y672000D01*
X1191000D01*
X1197500Y665500D01*
G01X1234000Y747500D02*
X1232081Y749419D01*
X1229411D01*
X1225550Y745558D01*
Y725070D01*
X1229070Y721550D01*
X1229808D01*
X1230950Y720408D01*
Y705414D01*
X1203759Y678223D01*
X1185281D01*
X1183631Y676573D01*
X1182815D01*
G01X1203181Y683968D02*
X1201194Y685955D01*
X1195486D01*
X1195464Y685977D01*
X1182785D01*
G01X1199551Y683968D02*
X1196083Y680500D01*
X1187236D01*
X1185856Y681880D01*
X1181218D01*
X1177128Y685970D01*
X1176520D01*
G01X1195937Y683849D02*
X1193588Y681500D01*
X1188500D01*
X1187000Y683000D01*
X1183428D01*
X1180469Y685959D01*
X1179663D01*
G01X1206781Y684003D02*
X1206497D01*
X1202545Y687955D01*
X1186109D01*
X1186026Y687872D01*
G01X1218040Y719850D02*
X1185222D01*
X1179703Y714331D01*
G01X1279500Y150500D02*
X1253340D01*
X1237608Y166232D01*
Y184108D01*
X1248700Y195200D01*
Y231300D01*
X1224500Y255500D01*
Y372000D01*
X1211500Y385000D01*
Y416272D01*
X1200772Y427000D01*
X1196000D01*
X1195000Y428000D01*
G01X1229000Y740000D02*
Y732758D01*
X1233950Y727808D01*
Y700450D01*
X1229500Y696000D01*
Y565758D01*
X1199550Y535808D01*
Y535000D01*
X1197675Y533125D01*
G01X1230219Y747469D02*
X1227050Y744300D01*
Y725692D01*
X1229692Y723050D01*
X1230430D01*
X1232450Y721030D01*
Y704792D01*
X1204231Y676573D01*
X1185965D01*
G01X1190000Y767500D02*
X1184500Y762000D01*
Y749500D01*
G01X1210800Y379700D02*
X1222500Y368000D01*
Y253500D01*
X1247000Y229000D01*
Y203000D01*
X1239000Y195000D01*
Y190500D01*
G01X1206400Y536800D02*
X1213150Y530050D01*
X1225487D01*
X1226487Y531050D01*
X1230308D01*
X1233582Y534324D01*
Y537808D01*
X1233532Y537858D01*
Y549203D01*
X1245500Y561171D01*
Y592500D01*
X1263000Y610000D01*
Y648258D01*
X1264242Y649500D01*
X1265329D01*
X1267501Y651672D01*
Y654101D01*
X1268805Y655405D01*
G01X1210000Y536800D02*
X1210200D01*
X1214950Y532050D01*
X1224658D01*
X1229500Y536892D01*
Y548000D01*
X1242123Y560623D01*
Y592123D01*
X1259450Y609450D01*
Y647537D01*
X1263413Y651500D01*
X1264500D01*
X1265500Y652500D01*
G01X1227500Y504246D02*
X1231370D01*
X1247291Y520167D01*
X1254927D01*
X1289500Y554740D01*
Y565671D01*
X1294000Y570171D01*
Y587500D01*
G01X1227500Y500500D02*
X1227563Y500437D01*
X1229374D01*
X1231183Y502246D01*
X1232199D01*
X1248120Y518167D01*
X1255756D01*
X1291500Y553911D01*
Y564842D01*
X1296000Y569342D01*
Y588829D01*
X1293500Y591329D01*
Y593000D01*
G01X1243000Y743000D02*
X1239450Y739450D01*
Y735708D01*
X1239050Y735308D01*
Y733692D01*
X1242000Y730742D01*
Y716253D01*
X1241500Y715753D01*
Y693500D01*
X1234000Y686000D01*
Y683829D01*
X1232999Y682828D01*
Y681172D01*
X1234000Y680171D01*
Y566039D01*
X1222000Y554039D01*
Y540000D01*
X1221500Y539500D01*
G01X1229000Y719600D02*
X1228898D01*
X1221000Y727498D01*
Y764750D01*
G01X1275885Y670525D02*
Y686615D01*
X1270340Y692160D01*
Y788434D01*
X1236016Y822758D01*
X1226742D01*
X1223000Y826500D01*
G01X1229807Y847000D02*
Y846334D01*
X1257950Y818191D01*
Y809250D01*
G01X1241000Y631500D02*
X1248750Y639250D01*
Y700054D01*
X1252000Y703304D01*
Y776965D01*
X1253500Y778465D01*
G01X1237500Y675500D02*
X1243000D01*
X1246000Y678500D01*
Y713180D01*
X1247000Y714180D01*
Y728500D01*
X1250000Y731500D01*
Y756000D01*
X1241500Y764500D01*
X1238000D01*
G01X1240016Y761500D02*
Y760984D01*
X1248500Y752500D01*
Y733000D01*
X1245500Y730000D01*
Y716924D01*
X1243500Y714924D01*
Y690500D01*
X1235000Y682000D01*
G01X1273702Y667662D02*
Y682798D01*
X1268000Y688500D01*
Y775742D01*
X1265550Y778192D01*
Y790393D01*
X1235222Y820722D01*
X1235258Y820758D01*
G01X1253000Y511000D02*
X1253500Y511500D01*
X1258000D01*
X1300000Y553500D01*
Y564000D01*
X1302500Y566500D01*
Y605000D01*
X1288000Y619500D01*
Y637500D01*
X1290000Y639500D01*
Y660000D01*
X1289500Y660500D01*
Y669000D01*
G01X1266500Y617500D02*
X1268000Y619000D01*
Y644500D01*
X1270755Y647255D01*
Y658003D01*
X1265258Y663500D01*
X1264883D01*
X1256712Y671671D01*
Y679420D01*
X1262170Y684878D01*
X1267500D01*
G01X1263121Y678621D02*
Y673879D01*
X1267950Y669050D01*
Y665050D01*
X1273055Y659945D01*
Y646055D01*
X1270501Y643501D01*
Y617999D01*
X1271000Y617500D01*
G01X1311300Y687500D02*
Y687200D01*
X1315000Y683500D01*
Y621500D01*
X1332367Y604133D01*
Y592029D01*
X1316300Y575962D01*
Y550586D01*
X1295910Y530196D01*
Y527932D01*
X1294768Y526790D01*
X1294432D01*
X1287250Y519608D01*
Y493788D01*
X1274250Y480788D01*
Y469750D01*
X1280450Y463550D01*
Y423950D01*
X1278050Y421550D01*
Y403950D01*
X1281000Y401000D01*
Y354000D01*
X1306000Y329000D01*
G01X1279000Y746575D02*
X1280500Y745075D01*
Y721186D01*
X1289812Y711874D01*
Y670312D01*
X1289500Y670000D01*
Y669000D01*
G01X1285700Y529700D02*
X1310500Y554500D01*
Y583550D01*
X1325950Y599000D01*
G01X1311300Y687500D02*
Y697565D01*
X1315800Y702065D01*
Y738100D01*
X1308100Y745800D01*
Y748200D01*
G01X1312000Y850500D02*
Y843500D01*
X1316500Y839000D01*
G01X1317000Y850500D02*
X1327200Y840300D01*
Y705700D01*
X1323500Y702000D01*
G01X1322000Y705500D02*
Y842484D01*
X1318113Y846371D01*
G54D19*
X1084646Y43267D03*
G54D29*
G01X-185516Y-508119D02*
Y-490619D01*
G01X-176346D02*
Y-508119D01*
G01Y-499369D02*
X-185516D01*
G01X-163431Y-508119D02*
X-165178Y-507827D01*
X-166706Y-506661D01*
X-168016Y-504911D01*
X-168890Y-502869D01*
X-169326Y-500536D01*
Y-498202D01*
X-168890Y-495869D01*
X-168016Y-493827D01*
X-166706Y-492078D01*
X-165178Y-490911D01*
X-163431Y-490619D01*
X-161685Y-490911D01*
X-160156Y-492078D01*
X-158846Y-493827D01*
X-157972Y-495869D01*
X-157536Y-498202D01*
Y-500536D01*
X-157972Y-502869D01*
X-158846Y-504911D01*
X-160156Y-506661D01*
X-161685Y-507827D01*
X-163431Y-508119D01*
G01X-150953D02*
Y-490619D01*
X-140909Y-508119D01*
Y-490619D01*
G01X-124064Y-508119D02*
X-132798D01*
Y-490619D01*
X-124064D01*
G01X-127558Y-499077D02*
X-132798D01*
G01X-110931Y-508119D02*
Y-500244D01*
X-115298Y-490619D01*
G01X-106564D02*
X-110931Y-500244D01*
G01X-74185Y-498786D02*
X-73311Y-497911D01*
X-72656Y-496453D01*
X-72219Y-494410D01*
X-72656Y-492661D01*
X-73529Y-491494D01*
X-75058Y-490619D01*
X-80953D01*
Y-508119D01*
X-73748D01*
X-72219Y-506953D01*
X-71346Y-505202D01*
X-70909Y-503161D01*
X-71346Y-501119D01*
X-72656Y-499369D01*
X-74185Y-498786D01*
X-80953D01*
G01X-63890Y-508119D02*
X-58431Y-490619D01*
X-52972Y-508119D01*
G01X-54938Y-501994D02*
X-61925D01*
G01X-45734Y-508119D02*
Y-490619D01*
X-41368D01*
X-39621Y-491494D01*
X-38311Y-492661D01*
X-37219Y-494410D01*
X-36346Y-496453D01*
X-36128Y-499369D01*
X-36346Y-502286D01*
X-37219Y-504328D01*
X-38311Y-506078D01*
X-39621Y-507244D01*
X-41368Y-508119D01*
X-45734D01*
G01X-22121Y-499369D02*
X-17754D01*
Y-504619D01*
X-19064Y-506369D01*
X-20593Y-507536D01*
X-22776Y-508119D01*
X-24959Y-507536D01*
X-26488Y-506369D01*
X-27798Y-504619D01*
X-28671Y-502577D01*
X-29108Y-500244D01*
Y-498202D01*
X-28671Y-496453D01*
X-27798Y-494410D01*
X-26488Y-492661D01*
X-25178Y-491494D01*
X-23431Y-490619D01*
X-21903D01*
X-20156Y-491202D01*
X-18846Y-492369D01*
G01X-1564Y-508119D02*
X-10298D01*
Y-490619D01*
X-1564D01*
G01X-5058Y-499077D02*
X-10298D01*
G01X7202Y-508119D02*
Y-490619D01*
X12661D01*
X14407Y-491494D01*
X15499Y-492661D01*
X15936Y-494994D01*
X15499Y-497328D01*
X14189Y-498786D01*
X12661Y-499661D01*
X7202D01*
G01X12661D02*
X15936Y-508119D01*
G01X48315Y-498786D02*
X49189Y-497911D01*
X49844Y-496453D01*
X50281Y-494410D01*
X49844Y-492661D01*
X48971Y-491494D01*
X47442Y-490619D01*
X41547D01*
Y-508119D01*
X48752D01*
X50281Y-506953D01*
X51154Y-505202D01*
X51591Y-503161D01*
X51154Y-501119D01*
X49844Y-499369D01*
X48315Y-498786D01*
X41547D01*
G01X58610Y-508119D02*
X64069Y-490619D01*
X69528Y-508119D01*
G01X67562Y-501994D02*
X60575D01*
G01X76984Y-505786D02*
X78731Y-507244D01*
X80696Y-508119D01*
X82442D01*
X84189Y-507244D01*
X85499Y-505786D01*
X86154Y-503744D01*
X85717Y-501703D01*
X84626Y-499952D01*
X82661Y-498786D01*
X80041Y-498202D01*
X78512Y-497036D01*
X77857Y-494994D01*
X78294Y-492952D01*
X79386Y-491494D01*
X80914Y-490619D01*
X82442D01*
X83971Y-491202D01*
X85281Y-492661D01*
G01X103436Y-508119D02*
X94702D01*
Y-490619D01*
X103436D01*
G01X99942Y-499077D02*
X94702D01*
G01X118315Y-498786D02*
X119189Y-497911D01*
X119844Y-496453D01*
X120281Y-494410D01*
X119844Y-492661D01*
X118971Y-491494D01*
X117442Y-490619D01*
X111547D01*
Y-508119D01*
X118752D01*
X120281Y-506953D01*
X121154Y-505202D01*
X121591Y-503161D01*
X121154Y-501119D01*
X119844Y-499369D01*
X118315Y-498786D01*
X111547D01*
G01X134069Y-508119D02*
X132322Y-507827D01*
X130794Y-506661D01*
X129484Y-504911D01*
X128610Y-502869D01*
X128174Y-500536D01*
Y-498202D01*
X128610Y-495869D01*
X129484Y-493827D01*
X130794Y-492078D01*
X132322Y-490911D01*
X134069Y-490619D01*
X135815Y-490911D01*
X137344Y-492078D01*
X138654Y-493827D01*
X139528Y-495869D01*
X139964Y-498202D01*
Y-500536D01*
X139528Y-502869D01*
X138654Y-504911D01*
X137344Y-506661D01*
X135815Y-507827D01*
X134069Y-508119D01*
G01X146110D02*
X151569Y-490619D01*
X157028Y-508119D01*
G01X155062Y-501994D02*
X148075D01*
G01X164702Y-508119D02*
Y-490619D01*
X170161D01*
X171907Y-491494D01*
X172999Y-492661D01*
X173436Y-494994D01*
X172999Y-497328D01*
X171689Y-498786D01*
X170161Y-499661D01*
X164702D01*
G01X170161D02*
X173436Y-508119D01*
G01X181766D02*
Y-490619D01*
X186132D01*
X187879Y-491494D01*
X189189Y-492661D01*
X190281Y-494410D01*
X191154Y-496453D01*
X191372Y-499369D01*
X191154Y-502286D01*
X190281Y-504328D01*
X189189Y-506078D01*
X187879Y-507244D01*
X186132Y-508119D01*
X181766D01*
G01X-37858Y-463119D02*
Y-445619D01*
X-32181Y-460202D01*
X-26504Y-445619D01*
Y-463119D01*
G01X-14681D02*
X-15991Y-462827D01*
X-17301Y-461661D01*
X-18175Y-459619D01*
X-18611Y-457286D01*
X-18175Y-454952D01*
X-17301Y-452911D01*
X-15991Y-451744D01*
X-14681Y-451453D01*
X-13371Y-451744D01*
X-12061Y-452911D01*
X-11188Y-454952D01*
X-10969Y-457286D01*
X-11188Y-459619D01*
X-12061Y-461661D01*
X-13371Y-462827D01*
X-14681Y-463119D01*
G01X6749Y-445619D02*
Y-463119D01*
G01Y-460495D02*
X5876Y-461953D01*
X4565Y-462827D01*
X3037Y-463119D01*
X1291Y-462536D01*
X-19Y-461078D01*
X-893Y-459328D01*
X-1111Y-457286D01*
X-893Y-455244D01*
X-19Y-453494D01*
X1291Y-452036D01*
X3037Y-451453D01*
X4565Y-451744D01*
X5657Y-452328D01*
X6749Y-453494D01*
G01X17044Y-455244D02*
X24031D01*
X23376Y-453202D01*
X22284Y-452036D01*
X20756Y-451453D01*
X19227Y-451744D01*
X17917Y-452619D01*
X17044Y-454661D01*
X16607Y-456411D01*
Y-458161D01*
X17044Y-459911D01*
X18136Y-461661D01*
X19446Y-462827D01*
X20974Y-463119D01*
X22502Y-462536D01*
X24031Y-460786D01*
G01X37819Y-463119D02*
Y-445619D01*
G01X281019Y-508119D02*
Y-490619D01*
X278399Y-494119D01*
G01Y-508119D02*
X283639D01*
G01X293716Y-504619D02*
X295025Y-506661D01*
X296772Y-507827D01*
X298737Y-508119D01*
X300484Y-507827D01*
X302231Y-506369D01*
X303322Y-504619D01*
X303541Y-502869D01*
X303104Y-500828D01*
X301576Y-499369D01*
X300047Y-498786D01*
X298082D01*
G01X300047D02*
X301357Y-497911D01*
X302449Y-496453D01*
X302886Y-494703D01*
X302449Y-492952D01*
X301357Y-491494D01*
X299392Y-490619D01*
X297427Y-490911D01*
X295462Y-492078D01*
G01X312307Y-506078D02*
X313836Y-507536D01*
X315582Y-508119D01*
X317329Y-507536D01*
X318857Y-505786D01*
X319949Y-503161D01*
X320386Y-500536D01*
Y-497328D01*
X319949Y-494703D01*
X318857Y-492369D01*
X317547Y-491202D01*
X316019Y-490619D01*
X314272Y-491202D01*
X312962Y-492369D01*
X312089Y-494119D01*
X311652Y-496453D01*
X312089Y-498494D01*
X313181Y-500536D01*
X314491Y-501703D01*
X316019Y-501994D01*
X317765Y-501411D01*
X319076Y-499952D01*
X320386Y-497328D01*
G01X336139Y-508119D02*
Y-490619D01*
X328060Y-503161D01*
X338978D01*
G01X351019Y-508119D02*
X352547Y-507827D01*
X354294Y-506953D01*
X355386Y-505495D01*
X355822Y-503452D01*
X355386Y-501411D01*
X354076Y-499661D01*
X352111Y-498786D01*
X349927D01*
X348617Y-498202D01*
X347525Y-496744D01*
X347089Y-494703D01*
X347744Y-492661D01*
X349272Y-491202D01*
X351019Y-490619D01*
X352765Y-491202D01*
X354294Y-492661D01*
X354949Y-494703D01*
X354512Y-496744D01*
X353421Y-498202D01*
X352111Y-498786D01*
X349927D01*
X347962Y-499661D01*
X346652Y-501411D01*
X346216Y-503452D01*
X346652Y-505495D01*
X347744Y-506953D01*
X349491Y-507827D01*
X351019Y-508119D01*
G01X267902Y-463119D02*
Y-445619D01*
X273142D01*
X274889Y-446494D01*
X276199Y-448536D01*
X276636Y-450869D01*
X276199Y-453202D01*
X275107Y-454952D01*
X273142Y-455828D01*
X267902D01*
G01X294572Y-447078D02*
X293262Y-446202D01*
X291734Y-445619D01*
X289987D01*
X288022Y-446494D01*
X286494Y-447952D01*
X285402Y-449703D01*
X284529Y-452619D01*
X284310Y-455244D01*
X284747Y-457869D01*
X285402Y-459619D01*
X286712Y-461369D01*
X288241Y-462536D01*
X289769Y-463119D01*
X291297D01*
X292826Y-462536D01*
X294136Y-461661D01*
X295228Y-460495D01*
G01X309015Y-453786D02*
X309889Y-452911D01*
X310544Y-451453D01*
X310981Y-449410D01*
X310544Y-447661D01*
X309671Y-446494D01*
X308142Y-445619D01*
X302247D01*
Y-463119D01*
X309452D01*
X310981Y-461953D01*
X311854Y-460202D01*
X312291Y-458161D01*
X311854Y-456119D01*
X310544Y-454369D01*
X309015Y-453786D01*
X302247D01*
G01X318219Y-468952D02*
X331319D01*
G01X337247Y-463119D02*
Y-445619D01*
X347291Y-463119D01*
Y-445619D01*
G01X359769Y-463119D02*
X358022Y-462827D01*
X356494Y-461661D01*
X355184Y-459911D01*
X354310Y-457869D01*
X353874Y-455536D01*
Y-453202D01*
X354310Y-450869D01*
X355184Y-448827D01*
X356494Y-447078D01*
X358022Y-445911D01*
X359769Y-445619D01*
X361515Y-445911D01*
X363044Y-447078D01*
X364354Y-448827D01*
X365228Y-450869D01*
X365664Y-453202D01*
Y-455536D01*
X365228Y-457869D01*
X364354Y-459911D01*
X363044Y-461661D01*
X361515Y-462827D01*
X359769Y-463119D01*
G01X410610Y-445619D02*
X416069Y-463119D01*
X421528Y-445619D01*
G01X437936Y-463119D02*
X429202D01*
Y-445619D01*
X437936D01*
G01X434442Y-454077D02*
X429202D01*
G01X446702Y-463119D02*
Y-445619D01*
X452161D01*
X453907Y-446494D01*
X454999Y-447661D01*
X455436Y-449994D01*
X454999Y-452328D01*
X453689Y-453786D01*
X452161Y-454661D01*
X446702D01*
G01X452161D02*
X455436Y-463119D01*
G01X468569Y-463702D02*
X468132Y-463411D01*
Y-462827D01*
X468569Y-462536D01*
X469006Y-462827D01*
Y-463411D01*
X468569Y-463702D01*
G01X433569Y-508119D02*
Y-490619D01*
X430949Y-494119D01*
G01Y-508119D02*
X436189D01*
G01X452815Y-498786D02*
X453689Y-497911D01*
X454344Y-496453D01*
X454781Y-494410D01*
X454344Y-492661D01*
X453471Y-491494D01*
X451942Y-490619D01*
X446047D01*
Y-508119D01*
X453252D01*
X454781Y-506953D01*
X455654Y-505202D01*
X456091Y-503161D01*
X455654Y-501119D01*
X454344Y-499369D01*
X452815Y-498786D01*
X446047D01*
G01X544152Y-445619D02*
Y-463119D01*
X552886D01*
G01X569949D02*
Y-451453D01*
G01Y-453494D02*
X569076Y-452328D01*
X567765Y-451744D01*
X566237Y-451453D01*
X564709Y-452036D01*
X563399Y-453202D01*
X562525Y-454952D01*
X562089Y-457286D01*
X562525Y-459619D01*
X563399Y-461369D01*
X564709Y-462536D01*
X566237Y-463119D01*
X567765Y-462827D01*
X569076Y-461953D01*
X569949Y-460786D01*
G01X578934Y-468369D02*
X580244Y-468952D01*
X581991Y-468369D01*
X583082Y-467203D01*
X583956Y-465744D01*
X585265Y-461078D01*
X588104Y-451453D01*
G01X581117D02*
X585265Y-461078D01*
G01X597744Y-455244D02*
X604731D01*
X604076Y-453202D01*
X602984Y-452036D01*
X601456Y-451453D01*
X599927Y-451744D01*
X598617Y-452619D01*
X597744Y-454661D01*
X597307Y-456411D01*
Y-458161D01*
X597744Y-459911D01*
X598836Y-461661D01*
X600146Y-462827D01*
X601674Y-463119D01*
X603202Y-462536D01*
X604731Y-460786D01*
G01X615462Y-463119D02*
Y-451453D01*
G01Y-453786D02*
X616554Y-452619D01*
X617646Y-451744D01*
X619174Y-451453D01*
X620265Y-451744D01*
X621576Y-452619D01*
G01X570402Y-490619D02*
Y-508119D01*
X579136D01*
G01X587466Y-504619D02*
X588775Y-506661D01*
X590522Y-507827D01*
X592487Y-508119D01*
X594234Y-507827D01*
X595981Y-506369D01*
X597072Y-504619D01*
X597291Y-502869D01*
X596854Y-500828D01*
X595326Y-499369D01*
X593797Y-498786D01*
X591832D01*
G01X593797D02*
X595107Y-497911D01*
X596199Y-496453D01*
X596636Y-494703D01*
X596199Y-492952D01*
X595107Y-491494D01*
X593142Y-490619D01*
X591177Y-490911D01*
X589212Y-492078D01*
G01X686702Y-490619D02*
Y-508119D01*
X695436D01*
G01X703984Y-513369D02*
X705294Y-513952D01*
X707041Y-513369D01*
X708132Y-512203D01*
X709006Y-510744D01*
X710315Y-506078D01*
X713154Y-496453D01*
G01X706167D02*
X710315Y-506078D01*
G01X722357Y-508119D02*
Y-496453D01*
G01Y-499369D02*
X723231Y-497911D01*
X724541Y-496744D01*
X726287Y-496453D01*
X727815Y-496744D01*
X729126Y-497911D01*
X729781Y-499952D01*
Y-508119D01*
G01X739857D02*
Y-496453D01*
G01Y-499369D02*
X740731Y-497911D01*
X742041Y-496744D01*
X743787Y-496453D01*
X745315Y-496744D01*
X746626Y-497911D01*
X747281Y-499952D01*
Y-508119D01*
G01X774202Y-490619D02*
Y-508119D01*
X782936D01*
G01X796069Y-496453D02*
Y-508119D01*
G01Y-491786D02*
X795632Y-491494D01*
Y-490911D01*
X796069Y-490619D01*
X796506Y-490911D01*
Y-491494D01*
X796069Y-491786D01*
G01X809857Y-496453D02*
Y-504619D01*
X810731Y-506661D01*
X812041Y-507827D01*
X813569Y-508119D01*
X815097Y-507827D01*
X816407Y-506661D01*
X817281Y-504619D01*
G01Y-508119D02*
Y-496453D01*
G01X686266Y-463119D02*
Y-445619D01*
X690632D01*
X692379Y-446494D01*
X693689Y-447661D01*
X694781Y-449410D01*
X695654Y-451453D01*
X695872Y-454369D01*
X695654Y-457286D01*
X694781Y-459328D01*
X693689Y-461078D01*
X692379Y-462244D01*
X690632Y-463119D01*
X686266D01*
G01X705294Y-455244D02*
X712281D01*
X711626Y-453202D01*
X710534Y-452036D01*
X709006Y-451453D01*
X707477Y-451744D01*
X706167Y-452619D01*
X705294Y-454661D01*
X704857Y-456411D01*
Y-458161D01*
X705294Y-459911D01*
X706386Y-461661D01*
X707696Y-462827D01*
X709224Y-463119D01*
X710752Y-462536D01*
X712281Y-460786D01*
G01X722794Y-461078D02*
X723886Y-462244D01*
X725414Y-463119D01*
X726724D01*
X728034Y-462536D01*
X728907Y-461661D01*
X729344Y-460495D01*
X729126Y-458744D01*
X728252Y-457869D01*
X724322Y-456119D01*
X723449Y-454077D01*
X723886Y-452619D01*
X724759Y-451744D01*
X726069Y-451453D01*
X727379Y-451744D01*
X728689Y-452619D01*
G01X743569Y-451453D02*
Y-463119D01*
G01Y-446786D02*
X743132Y-446494D01*
Y-445911D01*
X743569Y-445619D01*
X744006Y-445911D01*
Y-446494D01*
X743569Y-446786D01*
G01X758012Y-467494D02*
X759541Y-468661D01*
X761287Y-468952D01*
X762815Y-468661D01*
X764126Y-467203D01*
X764999Y-465161D01*
Y-451453D01*
G01Y-453786D02*
X764126Y-452619D01*
X762815Y-451744D01*
X761287Y-451453D01*
X759541Y-452036D01*
X758449Y-453202D01*
X757575Y-455244D01*
X757139Y-457286D01*
X757357Y-459036D01*
X758231Y-461078D01*
X759541Y-462536D01*
X761287Y-463119D01*
X762597Y-462827D01*
X764126Y-461661D01*
X764999Y-460495D01*
G01X774857Y-463119D02*
Y-451453D01*
G01Y-454369D02*
X775731Y-452911D01*
X777041Y-451744D01*
X778787Y-451453D01*
X780315Y-451744D01*
X781626Y-452911D01*
X782281Y-454952D01*
Y-463119D01*
G01X792794Y-455244D02*
X799781D01*
X799126Y-453202D01*
X798034Y-452036D01*
X796506Y-451453D01*
X794977Y-451744D01*
X793667Y-452619D01*
X792794Y-454661D01*
X792357Y-456411D01*
Y-458161D01*
X792794Y-459911D01*
X793886Y-461661D01*
X795196Y-462827D01*
X796724Y-463119D01*
X798252Y-462536D01*
X799781Y-460786D01*
G01X810512Y-463119D02*
Y-451453D01*
G01Y-453786D02*
X811604Y-452619D01*
X812696Y-451744D01*
X814224Y-451453D01*
X815315Y-451744D01*
X816626Y-452619D01*
G01X857269Y-508119D02*
Y-490619D01*
X854649Y-494119D01*
G01Y-508119D02*
X859889D01*
G01X874769D02*
Y-490619D01*
X872149Y-494119D01*
G01Y-508119D02*
X877389D01*
G01X888339Y-508702D02*
X896199Y-490619D01*
G01X909769Y-508119D02*
Y-490619D01*
X907149Y-494119D01*
G01Y-508119D02*
X912389D01*
G01X922466Y-504619D02*
X923775Y-506661D01*
X925522Y-507827D01*
X927487Y-508119D01*
X929234Y-507827D01*
X930981Y-506369D01*
X932072Y-504619D01*
X932291Y-502869D01*
X931854Y-500828D01*
X930326Y-499369D01*
X928797Y-498786D01*
X926832D01*
G01X928797D02*
X930107Y-497911D01*
X931199Y-496453D01*
X931636Y-494703D01*
X931199Y-492952D01*
X930107Y-491494D01*
X928142Y-490619D01*
X926177Y-490911D01*
X924212Y-492078D01*
G01X940839Y-508702D02*
X948699Y-490619D01*
G01X958121Y-493536D02*
X959431Y-491786D01*
X960959Y-490911D01*
X962706Y-490619D01*
X964889Y-491202D01*
X966417Y-492661D01*
X966854Y-494410D01*
X966636Y-496161D01*
X965762Y-497619D01*
X961396Y-500536D01*
X959431Y-502577D01*
X958121Y-505495D01*
X957684Y-508119D01*
X966854D01*
G01X979769Y-490619D02*
X978022Y-491202D01*
X976712Y-492661D01*
X975839Y-494410D01*
X975184Y-496744D01*
X974966Y-499369D01*
X975184Y-501994D01*
X975839Y-504328D01*
X976712Y-506078D01*
X978022Y-507536D01*
X979769Y-508119D01*
X981515Y-507536D01*
X982826Y-506078D01*
X983699Y-504328D01*
X984354Y-501994D01*
X984572Y-499369D01*
X984354Y-496744D01*
X983699Y-494410D01*
X982826Y-492661D01*
X981515Y-491202D01*
X979769Y-490619D01*
G01X997269Y-508119D02*
Y-490619D01*
X994649Y-494119D01*
G01Y-508119D02*
X999889D01*
G01X1017389D02*
Y-490619D01*
X1009310Y-503161D01*
X1020228D01*
G01X904966Y-463119D02*
Y-445619D01*
X909332D01*
X911079Y-446494D01*
X912389Y-447661D01*
X913481Y-449410D01*
X914354Y-451453D01*
X914572Y-454369D01*
X914354Y-457286D01*
X913481Y-459328D01*
X912389Y-461078D01*
X911079Y-462244D01*
X909332Y-463119D01*
X904966D01*
G01X931199D02*
Y-451453D01*
G01Y-453494D02*
X930326Y-452328D01*
X929015Y-451744D01*
X927487Y-451453D01*
X925959Y-452036D01*
X924649Y-453202D01*
X923775Y-454952D01*
X923339Y-457286D01*
X923775Y-459619D01*
X924649Y-461369D01*
X925959Y-462536D01*
X927487Y-463119D01*
X929015Y-462827D01*
X930326Y-461953D01*
X931199Y-460786D01*
G01X944769Y-445619D02*
Y-463119D01*
G01X941712Y-451453D02*
X947826D01*
G01X958994Y-455244D02*
X965981D01*
X965326Y-453202D01*
X964234Y-452036D01*
X962706Y-451453D01*
X961177Y-451744D01*
X959867Y-452619D01*
X958994Y-454661D01*
X958557Y-456411D01*
Y-458161D01*
X958994Y-459911D01*
X960086Y-461661D01*
X961396Y-462827D01*
X962924Y-463119D01*
X964452Y-462536D01*
X965981Y-460786D01*
M02*
